G04 ================== begin FILE IDENTIFICATION RECORD ==================*
G04 Layout Name:  14629-1a.brd*
G04 Film Name:    TSILK*
G04 File Format:  Gerber RS274X*
G04 File Origin:  Cadence Allegro 16.5-S037*
G04 Origin Date:  Tue Nov 25 11:50:43 2014*
G04 *
G04 Layer:  VIA CLASS/FILMMASKTOP*
G04 Layer:  REF DES/ASSEMBLY_TOP*
G04 Layer:  PACKAGE GEOMETRY/SILKSCREEN_TOP*
G04 Layer:  DRAWING FORMAT/LAYER_PCB_STORY*
G04 Layer:  DRAWING FORMAT/LAYER_SILK_T*
G04 Layer:  BOARD GEOMETRY/SILKSCREEN_TOP*
G04 *
G04 Offset:    (0.00 0.00)*
G04 Mirror:    No*
G04 Mode:      Positive*
G04 Rotation:  0*
G04 FullContactRelief:  No*
G04 UndefLineWidth:     6.00*
G04 ================== end FILE IDENTIFICATION RECORD ====================*
%FSLAX35Y35*MOIN*%
%IR0*IPPOS*OFA0.00000B0.00000*MIA0B0*SFA1.00000B1.00000*%
%ADD10C,.01*%
%ADD11C,.02*%
%ADD12C,.012*%
%ADD13C,.013*%
%ADD14C,.025*%
%ADD15C,.002*%
%ADD16C,.006*%
%ADD17C,.008*%
G75*
%LPD*%
G75*
G36*
G01X49042Y375502D02*
X58042D01*
Y367502D01*
X49042D01*
Y375502D01*
G37*
G36*
G01X277500Y83000D02*
Y78000D01*
X297500D01*
Y83000D01*
X277500D01*
G37*
G36*
G01X620735Y380276D02*
X618035D01*
Y377676D01*
X620735D01*
Y380276D01*
G37*
G36*
G01X353500Y215900D02*
X317100D01*
Y453100D01*
X353500D01*
Y215900D01*
G37*
G54D10*
G01X126489Y-19685D02*
G03X116016I-5236J0D01*
G01X157984D02*
G03X147511I-5236J0D01*
G01X220974D02*
G03X210502I-5236J0D01*
G01X189479D02*
G03X179007I-5236J0D01*
G01X283964D02*
G03X273492I-5236J0D01*
G01X252469D02*
G03X241997I-5236J0D01*
G54D11*
G01X-4246Y-109426D02*
Y-189426D01*
G01D02*
X1290354D01*
G01X-4246Y-144926D02*
X1290354D01*
G01X-8246Y-93426D02*
G02I-12000J0D01*
G01X-13396D02*
G02I-6850J0D01*
G01X-20246Y-109426D02*
Y-77426D01*
G01X-4246Y-93426D02*
X-36246D01*
G01X-4246Y-109426D02*
X1290354D01*
G01X6797Y193619D02*
X11797D01*
G01X-2303D02*
X2697D01*
G01X125000Y209500D02*
X289000D01*
Y143500D01*
X111000D01*
Y209500D01*
X125000D01*
G01X502854Y-109426D02*
Y-189426D01*
G01X504689Y167262D02*
X521289D01*
G01X479325Y167186D02*
X495925D01*
G01X470398Y186436D02*
X475398D01*
G01X529835Y167277D02*
X546435D01*
G01X636838Y80903D02*
X632188D01*
G01X623985Y336676D02*
Y353376D01*
G01X640354Y-109426D02*
Y-189426D01*
G01X755354Y-109426D02*
Y-189426D01*
G01X922854Y-109426D02*
Y-189426D01*
G01X1092854Y-109426D02*
Y-189426D01*
G01X1290354Y-109426D02*
Y-189426D01*
G01X1318354Y-93426D02*
G02I-12000J0D01*
G01X1313204D02*
G02I-6850J0D01*
G01X1306354Y-109426D02*
Y-77426D01*
G01X1322354Y-93426D02*
X1290354D01*
G54D12*
G01X0Y50259D02*
Y75460D01*
G01Y426594D02*
Y401397D01*
G01Y555771D02*
Y530574D01*
G01Y906909D02*
Y881711D01*
G01X77283Y0D02*
X107993D01*
G01X77283Y472441D02*
X107993D01*
G01X77283Y480315D02*
X107993D01*
G01X77283Y952756D02*
X107993D01*
G01X335552Y0D02*
X304843D01*
G01Y472441D02*
X335552D01*
G01X304843Y480315D02*
X335552D01*
G01X304843Y952756D02*
X335552D01*
G01X532402Y0D02*
X563111D01*
G01X584959Y161889D02*
G02I-4250J0D01*
G01X574959D02*
G02I-4250J0D01*
G01X584959Y171889D02*
G02I-4250J0D01*
G01Y181889D02*
G02I-4250J0D01*
G01Y191889D02*
G02I-4250J0D01*
G01Y204409D02*
G02I-4250J0D01*
G01Y214409D02*
G02I-4250J0D01*
G01X574959Y171889D02*
G02I-4250J0D01*
G01Y181889D02*
G02I-4250J0D01*
G01Y191889D02*
G02I-4250J0D01*
G01Y204409D02*
G02I-4250J0D01*
G01Y214409D02*
G02I-4250J0D01*
G01X584959Y224409D02*
G02I-4250J0D01*
G01Y234409D02*
G02I-4250J0D01*
G01Y256929D02*
G02I-4250J0D01*
G01Y266929D02*
G02I-4250J0D01*
G01Y276929D02*
G02I-4250J0D01*
G01X574959Y224409D02*
G02I-4250J0D01*
G01Y234409D02*
G02I-4250J0D01*
G01Y256929D02*
G02I-4250J0D01*
G01Y266929D02*
G02I-4250J0D01*
G01Y276929D02*
G02I-4250J0D01*
G01X584959Y244409D02*
G02I-4250J0D01*
G01X574959D02*
G02I-4250J0D01*
G01X584959Y286929D02*
G02I-4250J0D01*
G01X574959D02*
G02I-4250J0D01*
G01X564089Y427559D02*
G02I-4600J0D01*
G01X575496Y433071D02*
G02I-4000J0D01*
G01X585339D02*
G02I-4000J0D01*
G01X532402Y472441D02*
X563111D01*
G01X532402Y480315D02*
X563111D01*
G01X532402Y952756D02*
X563111D01*
G01X604959Y161889D02*
G02I-4250J0D01*
G01X594959D02*
G02I-4250J0D01*
G01X604959Y171889D02*
G02I-4250J0D01*
G01Y181889D02*
G02I-4250J0D01*
G01Y191889D02*
G02I-4250J0D01*
G01Y204409D02*
G02I-4250J0D01*
G01Y214409D02*
G02I-4250J0D01*
G01X594959Y171889D02*
G02I-4250J0D01*
G01Y181889D02*
G02I-4250J0D01*
G01Y191889D02*
G02I-4250J0D01*
G01Y204409D02*
G02I-4250J0D01*
G01Y214409D02*
G02I-4250J0D01*
G01X604959Y224409D02*
G02I-4250J0D01*
G01Y234409D02*
G02I-4250J0D01*
G01Y256929D02*
G02I-4250J0D01*
G01Y266929D02*
G02I-4250J0D01*
G01Y276929D02*
G02I-4250J0D01*
G01X594959Y224409D02*
G02I-4250J0D01*
G01Y234409D02*
G02I-4250J0D01*
G01Y256929D02*
G02I-4250J0D01*
G01Y266929D02*
G02I-4250J0D01*
G01Y276929D02*
G02I-4250J0D01*
G01Y244409D02*
G02I-4250J0D01*
G01X604959D02*
G02I-4250J0D01*
G01Y286929D02*
G02I-4250J0D01*
G01X594959D02*
G02I-4250J0D01*
G01X595182Y433071D02*
G02I-4000J0D01*
G01X608380Y442126D02*
G02I-4600J0D01*
G01X648267Y34437D02*
Y65146D01*
G01X640393Y34437D02*
Y65146D01*
G01X648267Y438004D02*
Y407295D01*
G01X640393Y438004D02*
Y407295D01*
G01X648267Y545462D02*
Y514753D01*
G01X640393Y545462D02*
Y514753D01*
G01X648267Y918320D02*
Y887611D01*
G01X640393Y918320D02*
Y887611D01*
G01X756261Y0D02*
X725552D01*
G01Y472441D02*
X756261D01*
G01X725552Y480315D02*
X756261D01*
G01X725552Y952756D02*
X756261D01*
G01X983820Y0D02*
X953111D01*
G01Y472441D02*
X983820D01*
G01X953111Y480315D02*
X983820D01*
G01X953111Y952756D02*
X983820D01*
G01X1180670Y0D02*
X1211380D01*
G01X1180670Y472441D02*
X1211380D01*
G01X1180670Y480315D02*
X1211380D01*
G01Y952756D02*
X1180670D01*
G01X1288660Y71044D02*
Y45847D01*
G01Y422182D02*
Y396985D01*
G01Y551359D02*
Y526162D01*
G01Y902497D02*
Y877296D01*
G54D13*
G01X631538Y81303D02*
Y79453D01*
G01X637438Y81303D02*
Y79453D01*
G54D14*
G01X47042Y367402D02*
Y359802D01*
G54D15*
G01X280670Y88090D02*
X280010D01*
G01X280110Y88180D02*
X280770D01*
G01X280860Y88290D02*
X280210D01*
G01X280310Y88380D02*
X280960D01*
G01X281060Y88490D02*
X280400D01*
G01X280500Y88590D02*
X281150D01*
G01X281250Y88680D02*
X280600D01*
G01X280690Y88790D02*
X281350D01*
G01X281440Y88880D02*
X280790D01*
G01X280880Y88990D02*
X281540D01*
G01X281640Y89090D02*
X280980D01*
G01X281080Y89180D02*
X281730D01*
G01X281830Y89290D02*
X281185D01*
G01X281180D02*
X281230D01*
G01X281270Y89380D02*
X281310D01*
G01X281270D02*
X281920D01*
G01X282020Y89490D02*
X281370D01*
G01X281470Y89590D02*
X282120D01*
G01X282220Y89680D02*
X281560D01*
G01X281660Y89790D02*
X282310D01*
G01X282410Y89880D02*
X281750D01*
G01X281850Y89990D02*
X282510D01*
G01X282600Y90090D02*
X281950D01*
G01X282050Y90180D02*
X282700D01*
G01X282790Y90290D02*
X282140D01*
G01X282240Y90380D02*
X282890D01*
G01X282990Y90490D02*
X282330D01*
G01X282430Y90590D02*
X283090D01*
G01X283180Y90680D02*
X282530D01*
G01X282620Y90790D02*
X283280D01*
G01X283470Y90990D02*
X282820D01*
G01X283010Y91180D02*
X283660D01*
G01X283620Y99330D02*
X278440Y104920D01*
G01X280140Y103090D02*
X280750D01*
G01X280850Y102990D02*
X280230D01*
G01X280330Y102880D02*
X280940D01*
G01X281030Y102790D02*
X280420D01*
G01X280510Y102680D02*
X281120D01*
G01X281220Y102590D02*
X280610D01*
G01X280700Y102490D02*
X281310D01*
G01X281400Y102380D02*
X280790D01*
G01X280880Y102290D02*
X281500D01*
G01X281590Y102180D02*
X280980D01*
G01X281070Y102090D02*
X281680D01*
G01X281780Y101990D02*
X281160D01*
G01X281250Y101880D02*
X281870D01*
G01X281960Y101790D02*
X281350D01*
G01X281440Y101680D02*
X282060D01*
G01X282150Y101590D02*
X281530D01*
G01X281620Y101490D02*
X282240D01*
G01X282340Y101380D02*
X281720D01*
G01X281810Y101290D02*
X282430D01*
G01X282520Y101180D02*
X281900D01*
G01X281990Y101090D02*
X282620D01*
G01X282710Y100990D02*
X282090D01*
G01X282180Y100880D02*
X282800D01*
G01X282890Y100790D02*
X282270D01*
G01X282370Y100680D02*
X282990D01*
G01X283080Y100590D02*
X282460D01*
G01X282550Y100490D02*
X283170D01*
G01X283270Y100380D02*
X282650D01*
G01X282830Y100180D02*
X284070D01*
G01X284080Y99990D02*
X283020D01*
G01X282770Y102280D02*
X283280D01*
G01X282730Y102240D02*
X282770Y102280D01*
G01X282730Y101780D02*
Y102240D01*
G01X282770Y101740D02*
X282730Y101780D01*
G01Y102180D02*
X292980D01*
G01X292910Y101990D02*
X282730D01*
G01Y101790D02*
X292750D01*
G01X285380Y103090D02*
X283950D01*
G01X283370Y102350D02*
X283280Y102280D01*
G01X283390Y102400D02*
X283370Y102350D01*
G01X283390Y102410D02*
Y102400D01*
G01X283510Y102660D02*
X283390Y102410D01*
G01X283530Y102670D02*
X283510Y102660D01*
G01X283960Y103090D02*
X283530Y102670D01*
G01X283290Y102290D02*
X284020D01*
G01X284130Y102620D02*
X284240Y102690D01*
G01X283960Y102450D02*
X284130Y102620D01*
G01X283940Y102340D02*
X283960Y102450D01*
G01X284030Y102280D02*
X283940Y102340D01*
G01X284100Y102590D02*
X283480D01*
G01X283430Y102490D02*
X284000D01*
G01X283950Y102380D02*
X283380D01*
G01X283640Y102790D02*
X285320D01*
G01Y102990D02*
X283850D01*
G01X284200Y99390D02*
X287430Y95910D01*
G01X284190Y99390D02*
X284200D01*
G01X284150Y99440D02*
X284190Y99390D01*
G01X284120Y99500D02*
X284150Y99440D01*
G01X283940Y101630D02*
X284120Y99500D01*
G01X284040Y101740D02*
X283940Y101630D01*
G01X284460Y95590D02*
X283990D01*
G01X283980Y95790D02*
X284440D01*
G01X284420Y95990D02*
X283960D01*
G01X283940Y96180D02*
X284410D01*
G01X284390Y96380D02*
X283920D01*
G01X283900Y96590D02*
X284370D01*
G01X284360Y96790D02*
X283890D01*
G01X283870Y96990D02*
X284340D01*
G01X284320Y97180D02*
X283850D01*
G01X283840Y97380D02*
X284310D01*
G01X284290Y97590D02*
X283820D01*
G01X283800Y97790D02*
X284270D01*
G01X284250Y97990D02*
X283790D01*
G01X283770Y98180D02*
X284240D01*
G01X284220Y98380D02*
X283750D01*
G01X283740Y98490D02*
X284250D01*
G01X284750Y98790D02*
X283720D01*
G01X283700Y98990D02*
X284570D01*
G01X283640Y99300D02*
X283620Y99330D01*
G01X283680Y99200D02*
X283640Y99300D01*
G01X283680Y99190D02*
Y99200D01*
G01Y99180D02*
Y99190D01*
G01X284380Y99180D02*
X283680D01*
G01X283580Y99380D02*
X284200D01*
G01X284130Y99490D02*
X283480D01*
G01X283390Y99590D02*
X284120D01*
G01X284110Y99680D02*
X283300D01*
G01X283200Y99790D02*
X284100D01*
G01X284090Y99880D02*
X283110D01*
G01X282920Y100090D02*
X284070D01*
G01X284060Y100290D02*
X283580D01*
G01X283370Y101740D02*
X282770D01*
G01X283470Y101650D02*
X283370Y101740D01*
G01X283590Y100300D02*
X283470Y101650D01*
G01X283430Y101680D02*
X283990D01*
G01X283940Y101590D02*
X283480D01*
G01X283490Y101490D02*
X283960D01*
G01Y101380D02*
X283490D01*
G01X283500Y101290D02*
X283970D01*
G01X283980Y101180D02*
X283510D01*
G01X283520Y101090D02*
X283990D01*
G01X284000Y100990D02*
X283530D01*
G01X283540Y100880D02*
X284010D01*
G01Y100790D02*
X283550D01*
G01Y100680D02*
X284020D01*
G01X284030Y100590D02*
X283570D01*
G01Y100490D02*
X284040D01*
G01X284050Y100380D02*
X283580D01*
G01X283420Y100230D02*
X278400Y105620D01*
G01X283530Y100200D02*
X283420Y100230D01*
G01X283590Y100300D02*
X283530Y100200D01*
G01X282740Y100290D02*
X283360D01*
G01X283680Y99180D02*
X284120Y94030D01*
G01X284130Y93990D02*
X284600D01*
G01X284610Y93790D02*
X284140D01*
G01X284160Y93590D02*
X284630D01*
G01X284650Y93380D02*
X284180D01*
G01X284200Y93180D02*
X284670D01*
G01X284710Y93090D02*
X284210D01*
G01X284220Y92440D02*
X284120Y92330D01*
G01X284250Y92510D02*
X284220Y92440D01*
G01X284070Y92290D02*
X284760D01*
G01Y92090D02*
X283880D01*
G01X283690Y91880D02*
X284780D01*
G01X284140Y91680D02*
X283490D01*
G01X283400Y91590D02*
X284050D01*
G01X283950Y91490D02*
X283300D01*
G01X283200Y91380D02*
X283860D01*
G01X283760Y91290D02*
X283110D01*
G01X282920Y91090D02*
X283570D01*
G01X283370Y90880D02*
X282720D01*
G01X284100Y94290D02*
X284570D01*
G01X284550Y94490D02*
X284090D01*
G01X284070Y94680D02*
X284540D01*
G01X284520Y94880D02*
X284050D01*
G01X284030Y95090D02*
X284500D01*
G01X284490Y95290D02*
X284020D01*
G01X284010Y95380D02*
X284480D01*
G01X284470Y95490D02*
X284000D01*
G01X283980Y95680D02*
X284450D01*
G01X284440Y95880D02*
X283970D01*
G01X283950Y96090D02*
X284420D01*
G01X284400Y96290D02*
X283930D01*
G01X283920Y96490D02*
X284380D01*
G01X284360Y96680D02*
X283900D01*
G01X283880Y96880D02*
X284350D01*
G01X284330Y97090D02*
X283860D01*
G01X283850Y97290D02*
X284310D01*
G01X284300Y97490D02*
X283830D01*
G01X283810Y97680D02*
X284280D01*
G01X284260Y97880D02*
X283790D01*
G01X283780Y98090D02*
X284240D01*
G01X284230Y98290D02*
X283760D01*
G01X284390Y98510D02*
X287120Y95570D01*
G01X284270Y98530D02*
X284390Y98510D01*
G01X284220Y98430D02*
X284270Y98530D01*
G01X284490Y95180D02*
X284030D01*
G01X284040Y94990D02*
X284510D01*
G01X284530Y94790D02*
X284060D01*
G01X284080Y94590D02*
X284550D01*
G01X284560Y94380D02*
X284090D01*
G01X284110Y94180D02*
X284580D01*
G01X284590Y94090D02*
X284120D01*
G01X284250Y92570D02*
Y92510D01*
G01X284120Y94030D02*
X284250Y92570D01*
G01X284240Y92490D02*
X284920D01*
G01X284770Y92310D02*
X284750Y92240D01*
G01X284820Y92390D02*
X284770Y92310D01*
G01X284750Y92180D02*
X283980D01*
G01X283790Y91990D02*
X284770D01*
G01X284790Y91680D02*
X284290D01*
G01X284260Y91720D02*
X284160Y91700D01*
G01X284530Y89280D02*
X284640D01*
G01X284530Y89290D02*
Y89280D01*
G01X284330Y91640D02*
X284530Y89290D01*
G01X284260Y91720D02*
X284330Y91640D01*
G01X284630Y89380D02*
X284520D01*
G01X284525D02*
X290120D01*
G01X290185Y89290D02*
X284530D01*
G01X284770Y88240D02*
X285660D01*
G01X284730Y88280D02*
X284770Y88240D01*
G01X284730Y88960D02*
Y88280D01*
G01X284700Y89030D02*
X284730Y88960D01*
G01X284550Y89190D02*
X284700Y89030D01*
G01X284540Y89210D02*
X284550Y89190D01*
G01X284530Y89270D02*
X284540Y89210D01*
G01X285700Y88290D02*
X284730D01*
G01Y88490D02*
X285700D01*
G01Y88680D02*
X284730D01*
G01Y88880D02*
X285700D01*
G01X284980Y89590D02*
X284510D01*
G01X284490Y89680D02*
X284960D01*
G01X284950Y89880D02*
X284480D01*
G01X284460Y90090D02*
X284930D01*
G01X284910Y90290D02*
X284440D01*
G01X284430Y90490D02*
X284900D01*
G01X284880Y90680D02*
X284410D01*
G01X284390Y90880D02*
X284860D01*
G01X284850Y91090D02*
X284380D01*
G01X284360Y91290D02*
X284830D01*
G01X284810Y91490D02*
X284350D01*
G01X284240Y92680D02*
X285110D01*
G01X285300Y92880D02*
X284220D01*
G01X284190Y93290D02*
X284660D01*
G01X284670Y93140D02*
X284220Y98430D01*
G01X284410Y98490D02*
X285030D01*
G01X285220Y98290D02*
X284600D01*
G01X284780Y98090D02*
X285400D01*
G01X284660Y98880D02*
X283710D01*
G01X283690Y99090D02*
X284480D01*
G01X284290Y99290D02*
X283650D01*
G01X284350Y102700D02*
X284240Y102690D01*
G01X284400Y102610D02*
X284350Y102700D01*
G01X284400Y102380D02*
Y102610D01*
G01X284300Y102280D02*
X284400Y102380D01*
G01X284030Y102280D02*
X284300D01*
G01X284230Y102680D02*
X283540D01*
G01X283960Y103090D02*
X284230Y103250D01*
G01X284350Y102680D02*
X285320D01*
G01Y102490D02*
X284400D01*
G01X284310Y102290D02*
X285420D01*
G01X284610Y93880D02*
X284140D01*
G01X284150Y93680D02*
X284620D01*
G01X284640Y93490D02*
X284170D01*
G01X284740Y93050D02*
X284840Y93080D01*
G01X284670Y93140D02*
X284740Y93050D01*
G01X284650Y89090D02*
X290430D01*
G01X284970Y89660D02*
X284750Y92240D01*
G01X284970Y89590D02*
Y89660D01*
G01X285070Y89500D02*
X284970Y89590D01*
G01X289170Y89500D02*
X285070D01*
G01X284820Y92380D02*
X284170D01*
G01X284250Y92590D02*
X285010D01*
G01X284830Y92390D02*
X284820D01*
G01X284830Y92400D02*
Y92390D01*
G01Y92400D02*
X287420Y95090D01*
G01X287230Y94880D02*
X286590D01*
G01X286390Y94680D02*
X287040D01*
G01X286850Y94490D02*
X286200D01*
G01X286010Y94290D02*
X286650D01*
G01X286560Y94180D02*
X285910D01*
G01X285960Y94240D02*
X284840Y93080D01*
G01X284850Y93090D02*
X285490D01*
G01X285400Y92990D02*
X284220D01*
G01X284230Y92790D02*
X285210D01*
G01X284950Y93180D02*
X285590D01*
G01X285690Y93290D02*
X285050D01*
G01X285140Y93380D02*
X285790D01*
G01X285880Y93490D02*
X285240D01*
G01X285330Y93590D02*
X285980D01*
G01X286070Y93680D02*
X285430D01*
G01X285530Y93790D02*
X286170D01*
G01X286270Y93880D02*
X285620D01*
G01X285720Y93990D02*
X286360D01*
G01X286460Y94090D02*
X285810D01*
G01X286640Y96090D02*
X287270D01*
G01X287080Y96290D02*
X286460D01*
G01X286270Y96490D02*
X286890D01*
G01X286710Y96680D02*
X286080D01*
G01X285990Y96790D02*
X286610D01*
G01X286520Y96880D02*
X285900D01*
G01X285810Y96990D02*
X286430D01*
G01X286330Y97090D02*
X285710D01*
G01X285620Y97180D02*
X286240D01*
G01X286150Y97290D02*
X285530D01*
G01X285430Y97380D02*
X286060D01*
G01X285960Y97490D02*
X285340D01*
G01X285250Y97590D02*
X285870D01*
G01X285780Y97680D02*
X285150D01*
G01X285060Y97790D02*
X285680D01*
G01X285590Y97880D02*
X284970D01*
G01X284880Y97990D02*
X285500D01*
G01X285310Y98180D02*
X284690D01*
G01X284500Y98380D02*
X285120D01*
G01X284940Y98590D02*
X283740D01*
G01X283730Y98680D02*
X284850D01*
G01X286700Y97960D02*
X286740Y97920D01*
G01X285320Y102380D02*
X284400D01*
G01X285420Y102280D02*
X285320Y102380D01*
G01X284400Y102590D02*
X285320D01*
G01X285400Y103120D02*
X285520Y103140D01*
G01X285320Y103020D02*
X285400Y103120D01*
G01X285320Y102380D02*
Y103020D01*
G01Y102880D02*
X283750D01*
G01X285420Y102280D02*
X291260D01*
G01X284790Y91790D02*
X283590D01*
G01X284330Y91590D02*
X284800D01*
G01X284820Y91380D02*
X284350D01*
G01X284370Y91180D02*
X284840D01*
G01X284850Y90990D02*
X284380D01*
G01X284400Y90790D02*
X284870D01*
G01X284890Y90590D02*
X284420D01*
G01X284440Y90380D02*
X284900D01*
G01X284920Y90180D02*
X284460D01*
G01X284470Y89990D02*
X284940D01*
G01X284960Y89790D02*
X284490D01*
G01X284720Y88990D02*
X285770D01*
G01X285700Y88280D02*
X285660Y88240D01*
G01X285700Y88920D02*
Y88280D01*
G01X285800Y89020D02*
X285700Y88920D01*
G01Y88380D02*
X284730D01*
G01Y88590D02*
X285700D01*
G01Y88790D02*
X284730D01*
G01X289270Y89970D02*
Y89980D01*
G01X289260Y89900D02*
X289270Y89970D01*
G01X289260Y89640D02*
Y89900D01*
G01X289270Y89620D02*
X289260Y89640D01*
G01X289170Y89500D02*
X289270Y89620D01*
G01Y89990D02*
X290040D01*
G01X290000Y89790D02*
X289260D01*
G01X289240Y89590D02*
X290040D01*
G01X287880Y95420D02*
Y95560D01*
G01X290580Y92520D02*
X287880Y95420D01*
G01X287900Y95590D02*
X287110D01*
G01X287120Y95430D02*
X285960Y94240D01*
G01X287120Y95570D02*
Y95430D01*
G01X286110Y94380D02*
X286750D01*
G01X286940Y94590D02*
X286300D01*
G01X286490Y94790D02*
X287140D01*
G01X287330Y94990D02*
X286680D01*
G01X287570Y95090D02*
X289250Y93270D01*
G01X287420Y95090D02*
X287570D01*
G01X286780D02*
X287420D01*
G01X289240Y93290D02*
X289870D01*
G01X289680Y93490D02*
X289050D01*
G01X288870Y93680D02*
X289500D01*
G01X289310Y93880D02*
X288680D01*
G01X288590Y93990D02*
X289220D01*
G01X289120Y94090D02*
X288490D01*
G01X288400Y94180D02*
X289030D01*
G01X288940Y94290D02*
X288310D01*
G01X288220Y94380D02*
X288850D01*
G01X288750Y94490D02*
X288120D01*
G01X288030Y94590D02*
X288660D01*
G01X288570Y94680D02*
X287940D01*
G01X287850Y94790D02*
X288480D01*
G01X288380Y94880D02*
X287750D01*
G01X287660Y94990D02*
X288290D01*
G01X288200Y95090D02*
X287550D01*
G01X287920Y95380D02*
X287070D01*
G01X287120Y95490D02*
X287880D01*
G01X288000Y95680D02*
X287010D01*
G01X286920Y95790D02*
X288100D01*
G01X288200Y95880D02*
X286830D01*
G01X286740Y95990D02*
X287360D01*
G01X287570Y95910D02*
X289000Y97380D01*
G01X287430Y95910D02*
X287570D01*
G01X288900Y97290D02*
X289540D01*
G01X289350Y97090D02*
X288710D01*
G01X288620Y96990D02*
X289250D01*
G01X289160Y96880D02*
X288520D01*
G01X288420Y96790D02*
X289060D01*
G01X288970Y96680D02*
X288330D01*
G01X288230Y96590D02*
X288870D01*
G01X288770Y96490D02*
X288130D01*
G01X288040Y96380D02*
X288680D01*
G01X288580Y96290D02*
X287940D01*
G01X287850Y96180D02*
X288480D01*
G01X288390Y96090D02*
X287750D01*
G01X287650Y95990D02*
X288290D01*
G01X288010Y95290D02*
X286980D01*
G01X286880Y95180D02*
X288100D01*
G01X287170Y96180D02*
X286550D01*
G01X286360Y96380D02*
X286990D01*
G01X286800Y96590D02*
X286180D01*
G01X286790Y97920D02*
X289280D01*
G01X286740D02*
X286790D01*
G01X289290Y97680D02*
X289930D01*
G01X289740Y97490D02*
X289100D01*
G01X290220Y97990D02*
X286700D01*
G01X286740Y98950D02*
X286790D01*
G01X286700Y98910D02*
X286740Y98950D01*
G01X286700Y97960D02*
Y98910D01*
G01Y98790D02*
X289960D01*
G01X289990Y98590D02*
X286700D01*
G01Y98380D02*
X290610D01*
G01X290410Y98180D02*
X286700D01*
G01X286760Y102840D02*
Y103180D01*
G01X286800Y102790D02*
X286760Y102840D01*
G01X289250Y102790D02*
X286800D01*
G01X289300Y102840D02*
X289250Y102790D01*
G01X289300Y103120D02*
Y102840D01*
G01X286760Y102880D02*
X289300D01*
G01Y102990D02*
X286760D01*
G01Y103090D02*
X289300D01*
G01X289810Y103150D02*
X290220Y103060D01*
G01X289300Y103120D02*
X289410Y103220D01*
G01X289910Y98950D02*
X286790D01*
G01X286700Y98880D02*
X289960D01*
G01X289950Y98910D02*
X289910Y98950D01*
G01X290130Y98560D02*
X290330Y98760D01*
G01X290020Y98530D02*
X290130Y98560D01*
G01X289960Y98630D02*
X290020Y98530D01*
G01X289960Y98810D02*
Y98630D01*
G01Y98820D02*
Y98810D01*
G01X289950Y98910D02*
X289960Y98820D01*
G01X290160Y98590D02*
X290800D01*
G01X289960Y98680D02*
X286700D01*
G01X288810Y97180D02*
X289450D01*
G01X289370Y97860D02*
X289280Y97920D01*
G01X289350Y97750D02*
X289370Y97860D01*
G01X289000Y97380D02*
X289350Y97750D01*
G01X289640Y97380D02*
X289000D01*
G01X289330Y97880D02*
X290120D01*
G01X290030Y97790D02*
X289360D01*
G01X289200Y97590D02*
X289830D01*
G01X289400Y93790D02*
X288770D01*
G01X288960Y93590D02*
X289590D01*
G01X289770Y93380D02*
X289140D01*
G01X289330Y93180D02*
X289960D01*
G01X290050Y93090D02*
X289420D01*
G01X289510Y92990D02*
X290150D01*
G01X290240Y92880D02*
X289610D01*
G01X289700Y92790D02*
X290330D01*
G01X290520Y92590D02*
X289890D01*
G01X290070Y92380D02*
X291210D01*
G01X291200Y92290D02*
X290170D01*
G01X289310Y90160D02*
X289270Y89980D01*
G01X289310Y90170D02*
Y90160D01*
G01X289420Y90480D02*
X289310Y90170D01*
G01X289430Y90490D02*
X289420Y90480D01*
G01X289640Y90800D02*
X289430Y90490D01*
G01X289650Y90810D02*
X289640Y90800D01*
G01X289890Y91030D02*
X289650Y90810D01*
G01X289900Y91030D02*
X289890D01*
G01X290020Y91110D02*
X289900Y91030D01*
G01X290030Y91120D02*
X290020Y91110D01*
G01X290090Y91150D02*
X290030Y91120D01*
G01X290250Y91220D02*
X290090Y91150D01*
G01X289260Y89880D02*
X290020D01*
G01X290060Y89490D02*
X284510D01*
G01X290050Y89510D02*
X290060Y89490D01*
G01X290000Y89770D02*
X290050Y89510D01*
G01X290000Y89780D02*
Y89770D01*
G01Y89800D02*
Y89780D01*
G01X284550Y89180D02*
X290290D01*
G01X290210Y89250D02*
X290150Y89340D01*
G01X290220Y89240D02*
X290210Y89250D01*
G01X290230Y89230D02*
X290220Y89240D01*
G01X290070Y89480D02*
X290060Y89490D01*
G01X290150Y89350D02*
X290070Y89480D01*
G01X290020Y89680D02*
X289260D01*
G01X289290Y90090D02*
X290060D01*
G01X290050Y90060D02*
X290000Y89800D01*
G01X290060Y90080D02*
X290050Y90060D01*
G01X290280Y89810D02*
X290290Y89830D01*
G01X290230Y90340D02*
X290450Y90500D01*
G01X290220Y90330D02*
X290230Y90340D01*
G01X290210Y90310D02*
X290220Y90330D01*
G01X290070Y90100D02*
X290210Y90310D01*
G01X290060Y90080D02*
X290070Y90100D01*
G01X290290Y90380D02*
X289390D01*
G01X289350Y90290D02*
X290190D01*
G01X290120Y90180D02*
X289310D01*
G01X289490Y90590D02*
X290750D01*
G01X290160Y91180D02*
X291830D01*
G01X291920Y91090D02*
X289980D01*
G01X289740Y90880D02*
X292110D01*
G01X292290Y90680D02*
X289570D01*
G01X290150Y89290D02*
X290190D01*
G01X290230Y89230D02*
X290450Y89070D01*
G01X290020Y88490D02*
X291570D01*
G01X291730Y88590D02*
X289840D01*
G01X289400Y89020D02*
X285800D01*
G01X289480Y88990D02*
X289400Y89020D01*
G01X289490Y88980D02*
X289480Y88990D01*
G01X289490Y88970D02*
Y88980D01*
G01X289530Y88900D02*
X289490Y88970D01*
G01X289540Y88900D02*
X289530D01*
G01X289550Y88890D02*
X289540Y88900D01*
G01X289620Y88790D02*
X289550Y88890D01*
G01X289630Y88780D02*
X289620Y88790D01*
G01X289860Y88560D02*
X289630Y88780D01*
G01Y88790D02*
X291970D01*
G01X289880Y88550D02*
X289860Y88560D01*
G01X290680Y88250D02*
X291020Y88260D01*
G01X290670Y88250D02*
X290680D01*
G01X290660D02*
X290670D01*
G01X290500Y88270D02*
X290660Y88250D01*
G01X290480Y88270D02*
X290500D01*
G01X289880Y88550D02*
X290480Y88270D01*
G01X291130Y88290D02*
X290460D01*
G01Y89060D02*
X290450Y89070D01*
G01X290480Y89060D02*
X290460D01*
G01X290650Y89000D02*
X290480Y89060D01*
G01X290870Y88990D02*
X290890D01*
G01X290740D02*
X290870D01*
G01X290670Y89000D02*
X290740Y88990D01*
G01X290650Y89000D02*
X290670D01*
G01X290310Y89620D02*
X290280Y89810D01*
G01X290320Y89590D02*
X290310Y89620D01*
G01X290490Y89370D02*
X290320Y89590D01*
G01X290510Y89360D02*
X290490Y89370D01*
G01X290680Y89280D02*
X290510Y89360D01*
G01X290690Y89280D02*
X290680D01*
G01X290730Y89270D02*
X290690Y89280D01*
G01X290790Y89270D02*
X290730D01*
G01X290810D02*
X290790D01*
G01X290840Y90300D02*
X290850D01*
G01X290750D02*
X290840D01*
G01X290730Y90290D02*
X290750Y90300D01*
G01X290420Y90130D02*
X290730Y90290D01*
G01X290400Y90110D02*
X290420Y90130D01*
G01X290290Y89830D02*
X290400Y90110D01*
G01X290460Y90510D02*
X290450Y90500D01*
G01X290480Y90510D02*
X290460D01*
G01X290650Y90570D02*
X290480Y90510D01*
G01X290670Y90570D02*
X290650D01*
G01X290740Y90580D02*
X290670Y90570D01*
G01X290760Y90590D02*
X290740Y90580D01*
G01X290820Y90590D02*
X290760D01*
G01X290850Y90580D02*
X290820Y90590D01*
G01X290430Y90490D02*
X289430D01*
G01X290340Y89970D02*
X291280D01*
G01X291300Y89770D02*
X290290D01*
G01X290340Y89570D02*
X291250D01*
G01X291070Y89370D02*
X290500D01*
G01X290810Y89270D02*
X290940Y89290D01*
G01X291140Y90160D02*
X290490D01*
G01X290890Y90580D02*
X291090Y90530D01*
G01X290850Y90580D02*
X290890D01*
G01X290340Y91250D02*
X290250Y91220D01*
G01X290350Y91260D02*
X290340Y91250D01*
G01X290490Y91290D02*
X290350Y91260D01*
G01X290570Y91310D02*
X290490Y91290D01*
G01X290350Y92090D02*
X289250Y93270D01*
G01X290610Y91810D02*
X290350Y92090D01*
G01X290640Y91760D02*
X290610Y91810D01*
G01X290670Y91610D02*
X290640Y91760D01*
G01X290680Y91590D02*
X290670Y91610D01*
G01X290680Y91570D02*
Y91590D01*
G01X290660Y91400D02*
X290680Y91570D01*
G01X290660Y91390D02*
Y91400D01*
G01X290570Y91310D02*
X290660Y91390D01*
G01X289790Y92680D02*
X290430D01*
G01X290750Y92580D02*
X291260Y98810D01*
G01X290690Y92500D02*
X290750Y92580D01*
G01X290580Y92520D02*
X290690Y92500D01*
G01X290350Y98790D02*
X290330Y98760D01*
G01X290990Y98790D02*
X290350D01*
G01D02*
X291160Y99630D01*
G01X290740Y99180D02*
X293000D01*
G01Y98990D02*
X290550D01*
G01X290250Y98680D02*
X290890D01*
G01X290700Y98490D02*
X286700D01*
G01Y98290D02*
X290510D01*
G01X290310Y98090D02*
X286700D01*
G01X290920Y94590D02*
X291380D01*
G01X291370Y94380D02*
X290900D01*
G01X290880Y94180D02*
X291350D01*
G01X291340Y93990D02*
X290870D01*
G01X290850Y93790D02*
X291320D01*
G01X291310Y93590D02*
X290840D01*
G01X290820Y93380D02*
X291290D01*
G01X291270Y93180D02*
X290810D01*
G01X290790Y92990D02*
X291250D01*
G01X291240Y92790D02*
X290770D01*
G01X290750Y92590D02*
X291220D01*
G01X291180Y92090D02*
X290350D01*
G01X290540Y91880D02*
X291180D01*
G01X291360Y91680D02*
X290660D01*
G01X290670Y91490D02*
X291550D01*
G01X290500Y102980D02*
X290220Y103060D01*
G01X290510Y102970D02*
X290500Y102980D01*
G01X290620Y102940D02*
X290510Y102970D01*
G01X290620Y102930D02*
Y102940D01*
G01X290730Y102890D02*
X290620Y102930D01*
G01X290740Y102880D02*
X290730Y102890D01*
G01X291600Y102880D02*
X290740D01*
G01X290460Y102990D02*
X291490D01*
G01X290100Y103090D02*
X291350D01*
G01Y102330D02*
X291260Y102280D01*
G01X291340Y102430D02*
X291350Y102330D01*
G01X291270Y102540D02*
X291340Y102430D01*
G01X291250Y102560D02*
X291270Y102540D01*
G01X290950Y102780D02*
X291250Y102560D01*
G01X290940Y102790D02*
X290950Y102780D01*
G01X290930Y102790D02*
X290940D01*
G01X290740Y102880D02*
X290930Y102790D01*
G01X291270Y102290D02*
X292990D01*
G01X292970Y102490D02*
X291310D01*
G01X291080Y102680D02*
X292890D01*
G01X293000Y100680D02*
X291220D01*
G01X291190Y99660D02*
X291160Y99630D01*
G01X291220Y99720D02*
X291190Y99660D01*
G01X291220Y100740D02*
Y99720D01*
G01X291120Y99590D02*
X291790D01*
G01X291960Y99790D02*
X291220D01*
G01Y99990D02*
X292150D01*
G01X292340Y100180D02*
X291220D01*
G01Y100290D02*
X293000D01*
G01Y100490D02*
X291220D01*
G01X291330Y100820D02*
X291430Y100920D01*
G01X291260Y100820D02*
X291330D01*
G01X291220Y100780D02*
X291260Y100820D01*
G01X291220Y100740D02*
Y100780D01*
G01X290930Y99380D02*
X293000D01*
G01X291720Y98680D02*
X291250D01*
G01X291090Y98890D02*
X287880Y95560D01*
G01X291200Y98910D02*
X291090Y98890D01*
G01X291260Y98810D02*
X291200Y98910D01*
G01X290980Y95380D02*
X291450D01*
G01X291460Y95490D02*
X290990D01*
G01X291010Y95680D02*
X291480D01*
G01X291490Y95880D02*
X291030D01*
G01X291040Y96090D02*
X291510D01*
G01X291520Y96290D02*
X291060D01*
G01X291070Y96490D02*
X291540D01*
G01X291560Y96680D02*
X291090D01*
G01X291110Y96880D02*
X291570D01*
G01X291590Y97090D02*
X291120D01*
G01X291140Y97290D02*
X291610D01*
G01X291620Y97490D02*
X291160D01*
G01X291170Y97680D02*
X291640D01*
G01X291650Y97880D02*
X291190D01*
G01X291200Y98090D02*
X291670D01*
G01X291690Y98290D02*
X291220D01*
G01X291240Y98490D02*
X291700D01*
G01X291090Y98880D02*
X290450D01*
G01X290970Y95180D02*
X291440D01*
G01X291420Y94990D02*
X290950D01*
G01X290940Y94790D02*
X291400D01*
G01X291390Y94680D02*
X290930D01*
G01X290910Y94490D02*
X291380D01*
G01X291360Y94290D02*
X290890D01*
G01X290880Y94090D02*
X291350D01*
G01X291330Y93880D02*
X290860D01*
G01X290850Y93680D02*
X291310D01*
G01X291300Y93490D02*
X290830D01*
G01X290810Y93290D02*
X291280D01*
G01X291260Y93090D02*
X290800D01*
G01X290780Y92880D02*
X291250D01*
G01X291230Y92680D02*
X290760D01*
G01X291220Y92490D02*
X289980D01*
G01X290260Y92180D02*
X291190D01*
G01X291180Y91990D02*
X290450D01*
G01X290620Y91790D02*
X291260D01*
G01X291200Y91850D02*
X292160Y90830D01*
G01X292480Y90490D02*
X291150D01*
G01X291130Y90510D02*
X291090Y90530D01*
G01X291130Y90510D02*
X291440Y90250D01*
G01X291210Y90070D02*
X290380D01*
G01X290300Y89870D02*
X291290D01*
G01X291100Y90200D02*
X290850Y90300D01*
G01X291120Y90190D02*
X291100Y90200D01*
G01X291270Y89990D02*
X291120Y90190D01*
G01X291280Y89960D02*
X291270Y89990D01*
G01X290940Y90270D02*
X290670D01*
G01X290960Y89290D02*
X290940D01*
G01X291180Y89430D02*
X290960Y89290D01*
G01X291190Y89450D02*
X291180Y89430D01*
G01X291300Y89680D02*
X291190Y89450D01*
G01X291310Y89700D02*
X291300Y89680D01*
G01X291280Y89960D02*
X291310Y89700D01*
G01X291150Y89090D02*
X292170D01*
G01X291030Y88260D02*
X291020D01*
G01X291320Y88330D02*
X291030Y88260D01*
G01X291330Y88340D02*
X291320Y88330D01*
G01X291840Y88650D02*
X291330Y88340D01*
G01X291090Y89040D02*
X291130Y89060D01*
G01X290890Y88990D02*
X291090Y89040D01*
G01X291200Y89470D02*
X290420D01*
G01X290300Y89660D02*
X291300D01*
G01X291190Y91870D02*
X291170Y91940D01*
G01X291200Y91860D02*
X291190Y91870D01*
G01X291200Y91850D02*
Y91860D01*
G01X292210Y103040D02*
X292220D01*
G01X292100Y103010D02*
X292210Y103040D01*
G01X292090Y103010D02*
X292100D01*
G01X291960Y102960D02*
X292090Y103010D01*
G01X291960Y102950D02*
Y102960D01*
G01X291900Y102920D02*
X291960Y102950D01*
G01X291880Y102900D02*
X291900Y102920D01*
G01X291820Y102850D02*
X291880Y102900D01*
G01X291800Y102830D02*
X291820Y102850D01*
G01X291660Y102830D02*
X291800D01*
G01X291480Y103000D02*
X291660Y102830D01*
G01X291470Y103010D02*
X291480Y103000D01*
G01X290970Y103320D02*
X291470Y103010D01*
G01X292030Y102990D02*
X292550D01*
G01X292600Y101680D02*
X291440D01*
G01X291490Y101630D02*
X291430Y100920D01*
G01X291400Y100880D02*
X291950D01*
G01X292240Y101610D02*
X292270Y101600D01*
G01X292160Y101620D02*
X292240Y101610D01*
G01X292090Y101640D02*
X292160Y101620D01*
G01X292080Y101640D02*
X292090D01*
G01X291950Y101550D02*
X292080Y101640D01*
G01X291900Y100940D02*
X291950Y101550D01*
G01X292000Y100830D02*
X291900Y100940D01*
G01X292000Y101590D02*
X291490D01*
G01X291390Y101740D02*
X284040D01*
G01X291490Y101630D02*
X291390Y101740D01*
G01X291030Y99490D02*
X291850D01*
G01X291820Y99640D02*
X292370Y100220D01*
G01X291790Y99590D02*
X291820Y99640D01*
G01X291790Y99550D02*
Y99590D01*
G01X291890Y99440D02*
X291790Y99550D01*
G01X292250Y100090D02*
X291220D01*
G01Y99880D02*
X292050D01*
G01X291860Y99680D02*
X291200D01*
G01X291220Y98880D02*
X291750D01*
G01X291740Y98870D02*
X291170Y91940D01*
G01X291450Y91590D02*
X290680D01*
G01X290650Y91380D02*
X291640D01*
G01X291730Y91290D02*
X290460D01*
G01X289850Y90990D02*
X292010D01*
G01X292200Y90790D02*
X289630D01*
G01X289480Y88990D02*
X292110D01*
G01X291930Y88740D02*
X291840Y88650D01*
G01X291990Y88810D02*
X291930Y88740D01*
G01X292120Y89000D02*
X291990Y88810D01*
G01X291880Y88680D02*
X289730D01*
G01X289550Y88880D02*
X292040D01*
G01X292240Y89250D02*
X292300Y89420D01*
G01X292200Y89150D02*
X292240Y89250D01*
G01X292200Y89140D02*
Y89150D01*
G01X292130Y89010D02*
X292200Y89140D01*
G01X292120Y89000D02*
X292130Y89010D01*
G01X292290Y89380D02*
X291475D01*
G01X291480D02*
X291540D01*
G01X291440Y89320D02*
X291130Y89060D01*
G01X291470Y89370D02*
X291440Y89320D01*
G01X291270Y89180D02*
X292220D01*
G01X292250Y89290D02*
X291460D01*
G01X291470Y90200D02*
X291440Y90250D01*
G01X291590Y89810D02*
X291470Y90200D01*
G01X291590Y89750D02*
Y89810D01*
G01X291470Y89370D02*
X291590Y89750D01*
G01X291400Y90290D02*
X292660D01*
G01X292850Y90090D02*
X291510D01*
G01X291570Y89880D02*
X293030D01*
G01X292330Y89680D02*
X291570D01*
G01X291510Y89490D02*
X292310D01*
G01X291400Y88380D02*
X290240D01*
G01X290940Y94880D02*
X291410D01*
G01X291430Y95090D02*
X290960D01*
G01X290980Y95290D02*
X291440D01*
G01X291470Y95590D02*
X291000D01*
G01X291010Y95790D02*
X291480D01*
G01X291500Y95990D02*
X291030D01*
G01X291050Y96180D02*
X291510D01*
G01X291530Y96380D02*
X291070D01*
G01X291080Y96590D02*
X291550D01*
G01X291570Y96790D02*
X291100D01*
G01X291110Y96990D02*
X291580D01*
G01X291600Y97180D02*
X291130D01*
G01X291150Y97380D02*
X291610D01*
G01X291630Y97590D02*
X291160D01*
G01X291180Y97790D02*
X291640D01*
G01X291660Y97990D02*
X291200D01*
G01X291210Y98180D02*
X291680D01*
G01X291700Y98380D02*
X291230D01*
G01X291240Y98590D02*
X291710D01*
G01X291730Y98790D02*
X291260D01*
G01X291740Y98870D02*
X291830Y98960D01*
G01X292160Y100820D02*
X292280D01*
G01X292000Y100830D02*
X292160Y100820D01*
G01X291910Y100990D02*
X291440D01*
G01X291450Y101090D02*
X291920D01*
G01Y101180D02*
X291460D01*
G01Y101290D02*
X291930D01*
G01X291940Y101380D02*
X291470D01*
G01X291480Y101490D02*
X291950D01*
G01X291860Y102880D02*
X292720D01*
G01X292830Y102790D02*
X290940D01*
G01X291220Y102590D02*
X292940D01*
G01X292980Y102380D02*
X291350D01*
G01X292840Y101880D02*
X282730D01*
G01Y102090D02*
X292940D01*
G01X292960Y98960D02*
X291830D01*
G01X291890Y99440D02*
X292440D01*
G01X293000Y99290D02*
X290830D01*
G01X290640Y99090D02*
X293000D01*
G01Y100380D02*
X291220D01*
G01Y100590D02*
X293000D01*
G01Y100790D02*
X291220D01*
G01X292380Y90590D02*
X290830D01*
G01X291270Y90380D02*
X292570D01*
G01X292750Y90180D02*
X291480D01*
G01X291530Y89990D02*
X292940D01*
G01X292320Y89590D02*
X291540D01*
G01X291590Y89790D02*
X292400D01*
G01X295970Y86740D02*
X292160Y90830D01*
G01X278700Y86720D02*
X284120Y92330D01*
G01X278670Y86690D02*
X278700Y86720D01*
G01X278680Y86670D02*
X278670Y86690D01*
G01X278990Y86400D02*
X278680Y86670D01*
G01X279020Y86390D02*
X278990Y86400D01*
G01X279040D02*
X279020Y86390D01*
G01X284160Y91700D02*
X279040Y86400D01*
G01X279120Y86490D02*
X278890D01*
G01X278770Y86590D02*
X279220D01*
G01X279320Y86680D02*
X278670D01*
G01X278760Y86790D02*
X279420D01*
G01X279510Y86880D02*
X278860D01*
G01X278950Y86990D02*
X279610D01*
G01X279700Y87090D02*
X279050D01*
G01X279140Y87180D02*
X279800D01*
G01X279900Y87290D02*
X279240D01*
G01X279340Y87380D02*
X279990D01*
G01X280090Y87490D02*
X279440D01*
G01X279530Y87590D02*
X280190D01*
G01X280280Y87680D02*
X279630D01*
G01X279730Y87790D02*
X280380D01*
G01X280480Y87880D02*
X279820D01*
G01X279920Y87990D02*
X280570D01*
G01X278370Y105600D02*
X278400Y105620D01*
G01X278370Y105060D02*
Y105600D01*
G01X278380Y105040D02*
X278370Y105060D01*
G01X278430Y104930D02*
X278380Y105040D01*
G01X278440Y104920D02*
X278430Y104930D01*
G01X278370Y105590D02*
X278430D01*
G01X278370Y105490D02*
X278520D01*
G01X278610Y105380D02*
X278370D01*
G01Y105290D02*
X278710D01*
G01X278800Y105180D02*
X278370D01*
G01Y105090D02*
X278890D01*
G01X278990Y104990D02*
X278400D01*
G01X278470Y104880D02*
X279080D01*
G01X279170Y104790D02*
X278560D01*
G01X278650Y104680D02*
X279260D01*
G01X279360Y104590D02*
X278750D01*
G01X278840Y104490D02*
X279450D01*
G01X279540Y104380D02*
X278930D01*
G01X279020Y104290D02*
X279640D01*
G01X279730Y104180D02*
X279120D01*
G01X279210Y104090D02*
X279820D01*
G01X279920Y103990D02*
X279300D01*
G01X279400Y103880D02*
X280010D01*
G01X280100Y103790D02*
X279490D01*
G01X279580Y103680D02*
X280200D01*
G01X280290Y103590D02*
X279680D01*
G01X279770Y103490D02*
X280380D01*
G01X280480Y103380D02*
X279860D01*
G01X279950Y103290D02*
X280570D01*
G01X280660Y103180D02*
X280050D01*
G01X284410Y103670D02*
X284440Y103690D01*
G01X284400Y103640D02*
X284410Y103670D01*
G01X284400Y103440D02*
Y103640D01*
G01X284390Y103400D02*
X284400Y103440D01*
G01X284370Y103350D02*
X284390Y103400D01*
G01X284320Y103290D02*
X284370Y103350D01*
G01X284230Y103250D02*
X284320Y103290D01*
G01X284440Y103680D02*
X285270D01*
G01X284400Y103490D02*
X287290D01*
G01X287280Y103290D02*
X284300D01*
G01X286650D02*
X286760Y103180D01*
G01X286380Y103260D02*
X286650Y103290D01*
G01X286100Y103230D02*
X286380Y103260D01*
G01X285980Y103220D02*
X286100Y103230D01*
G01X285880Y103200D02*
X285980Y103220D01*
G01X285630Y103160D02*
X285880Y103200D01*
G01X285620Y103160D02*
X285630D01*
G01X285530Y103140D02*
X285620Y103160D01*
G01X285520Y103140D02*
X285530D01*
G01X285260Y103690D02*
X284440D01*
G01X285280Y103680D02*
X285260Y103690D01*
G01X285310Y103670D02*
X285280Y103680D01*
G01X285340Y103650D02*
X285310Y103670D01*
G01X285420Y103630D02*
X285340Y103650D01*
G01X285440Y103640D02*
X285420Y103630D01*
G01X285680Y103680D02*
X285440Y103640D01*
G01X286180Y103750D02*
X285680Y103680D01*
G01X286300Y103760D02*
X286180Y103750D01*
G01X286360Y103760D02*
X286300D01*
G01X286520Y103780D02*
X286360Y103760D01*
G01X286660Y103790D02*
X286520Y103780D01*
G01X284120Y103180D02*
X285770D01*
G01X289330Y103790D02*
X286640D01*
G01X286660D02*
X286760Y103890D01*
G01X286750Y103180D02*
X289380D01*
G01X288850Y103400D02*
Y103360D01*
G01X288750Y103500D02*
X288850Y103400D01*
G01X287310Y103500D02*
X288750D01*
G01X287210Y103400D02*
X287310Y103500D01*
G01X287210Y103360D02*
Y103400D01*
G01X287310Y103250D02*
X287210Y103360D01*
G01X288750Y103250D02*
X287310D01*
G01X288850Y103360D02*
X288750Y103250D01*
G01X288850Y103380D02*
X290820D01*
G01X290530Y103490D02*
X288760D01*
G01X286760Y103920D02*
Y103890D01*
G01X286800Y103960D02*
X286760Y103920D01*
G01X289250Y103960D02*
X286800D01*
G01X289300Y103920D02*
X289250Y103960D01*
G01X289300Y103820D02*
Y103920D01*
G01X286750Y103880D02*
X289300D01*
G01X287210Y103380D02*
X284380D01*
G01X284400Y103590D02*
X290160D01*
G01X289380Y103720D02*
X289300Y103820D01*
G01X289430Y103720D02*
X289380D01*
G01X289990Y103630D02*
X289430Y103720D01*
G01X290170Y103590D02*
X289990Y103630D01*
G01X289610Y103680D02*
X285740D01*
G01X289520Y103200D02*
X289810Y103150D01*
G01X289490Y103200D02*
X289520D01*
G01X289410Y103220D02*
X289490Y103200D01*
G01X289600Y103180D02*
X291190D01*
G01X290290Y103550D02*
X290170Y103590D01*
G01X290400Y103530D02*
X290290Y103550D01*
G01X290640Y103450D02*
X290400Y103530D01*
G01X290750Y103410D02*
X290640Y103450D01*
G01X290810Y103390D02*
X290750Y103410D01*
G01X291030Y103290D02*
X288780D01*
G01X290960Y103330D02*
X290810Y103390D01*
G01X290970Y103320D02*
X290960Y103330D01*
G01X292220Y103040D02*
X292280Y103050D01*
G01X292220Y89290D02*
X292250D01*
G01X292350Y103050D02*
X292280D01*
G01X292360Y103040D02*
X292350Y103050D01*
G01X292620Y102970D02*
X292360Y103040D01*
G01X292630Y102960D02*
X292620Y102970D01*
G01X292830Y102790D02*
X292630Y102960D01*
G01X292840Y102780D02*
X292830Y102790D01*
G01X292960Y102550D02*
X292840Y102780D01*
G01X292970Y102530D02*
X292960Y102550D01*
G01X292990Y102250D02*
X292970Y102530D01*
G01X292990Y102240D02*
Y102250D01*
G01X292910Y101980D02*
X292990Y102240D01*
G01X292900Y101970D02*
X292910Y101980D01*
G01X292740Y101770D02*
X292900Y101970D01*
G01X292730Y101750D02*
X292740Y101770D01*
G01X292500Y101630D02*
X292730Y101750D01*
G01X292480Y101630D02*
X292500D01*
G01X292360Y101610D02*
X292480Y101630D01*
G01X292350Y101610D02*
X292360D01*
G01X292290Y101600D02*
X292350Y101610D01*
G01X292270Y101600D02*
X292290D01*
G01X293250Y101790D02*
X293880D01*
G01X293980Y101880D02*
X293350D01*
G01X293440Y101990D02*
X294080D01*
G01X294170Y102090D02*
X293540D01*
G01X293640Y102180D02*
X294270D01*
G01X294360Y102290D02*
X293740D01*
G01X293830Y102380D02*
X294460D01*
G01X294560Y102490D02*
X293930D01*
G01X294030Y102590D02*
X294660D01*
G01X294850Y102790D02*
X294220D01*
G01X294410Y102990D02*
X295040D01*
G01X293790Y101680D02*
X293160D01*
G01X293060Y101590D02*
X293690D01*
G01X293590Y101490D02*
X292960D01*
G01X292860Y101380D02*
X293500D01*
G01X293400Y101290D02*
X292770D01*
G01X292670Y101180D02*
X293310D01*
G01X293210Y101090D02*
X292580D01*
G01X292480Y100990D02*
X293110D01*
G01X293000Y98980D02*
X292960Y98960D01*
G01X293000Y98990D02*
Y98980D01*
G01Y100810D02*
Y98990D01*
G01Y100820D02*
Y100810D01*
G01X293030Y100900D02*
X293000Y100820D01*
G01X292480Y100240D02*
X292370Y100220D01*
G01X292540Y100140D02*
X292480Y100240D01*
G01X292540Y99540D02*
Y100140D01*
G01X292440Y99440D02*
X292540Y99540D01*
G01X292510Y100180D02*
X293000D01*
G01Y100090D02*
X292540D01*
G01Y99990D02*
X293000D01*
G01Y99880D02*
X292540D01*
G01Y99790D02*
X293000D01*
G01Y99680D02*
X292540D01*
G01Y99590D02*
X293000D01*
G01Y99490D02*
X292490D01*
G01X292280Y100820D02*
X292350Y100850D01*
G01X292380Y100880D02*
X293020D01*
G01X293130Y89790D02*
X292440D01*
G01X292300Y89440D02*
Y89420D01*
G01X292340Y89710D02*
X292300Y89440D01*
G01X292400Y89790D02*
X292340Y89710D01*
G01X292400Y89790D02*
X292510Y89770D01*
G01X292590Y89680D02*
X293220D01*
G01X293310Y89590D02*
X292680D01*
G01X292770Y89490D02*
X293410D01*
G01X293460Y89380D02*
X293500D01*
G01X293510D02*
X292870D01*
G01X292960Y89290D02*
X293595D01*
G01X293590D02*
X293540D01*
G01X293695Y89180D02*
X293050D01*
G01X293140Y89090D02*
X293780D01*
G01X293870Y88990D02*
X293235D01*
G01X293335Y88880D02*
X293970D01*
G01X294060Y88790D02*
X293420D01*
G01X293525Y88680D02*
X294150D01*
G01X294250Y88590D02*
X293610D01*
G01X293700Y88490D02*
X294340D01*
G01X294430Y88380D02*
X293790D01*
G01X293880Y88290D02*
X294530D01*
G01X294710Y88090D02*
X294070D01*
G01X293980Y88180D02*
X294620D01*
G01X294800Y87990D02*
X294160D01*
G01X294260Y87880D02*
X294900D01*
G01X294990Y87790D02*
X294350D01*
G01X294440Y87680D02*
X295080D01*
G01X295180Y87590D02*
X294530D01*
G01X294630Y87490D02*
X295270D01*
G01X295360Y87380D02*
X294720D01*
G01X294810Y87290D02*
X295460D01*
G01X295550Y87180D02*
X294910D01*
G01X295000Y87090D02*
X295640D01*
G01X295830Y86880D02*
X295190D01*
G01X295370Y86680D02*
X295980D01*
G01X295640Y86400D02*
X295660Y86380D01*
G01X292510Y89770D02*
X295640Y86400D01*
G01X295560Y86490D02*
X295780D01*
G01X292350Y100850D02*
X296930Y105590D01*
G01X296960Y104980D02*
X293030Y100900D01*
G01X294120Y102680D02*
X294750D01*
G01X294940Y102880D02*
X294310D01*
G01X294510Y103090D02*
X295140D01*
G01X295740Y86990D02*
X295090D01*
G01X295280Y86790D02*
X295920D01*
G01X295690Y86400D02*
X295660Y86380D01*
G01X295980Y86690D02*
X295690Y86400D01*
G01X295990Y86710D02*
X295980Y86690D01*
G01Y86720D02*
X295990Y86710D01*
G01X295970Y86740D02*
X295980Y86720D01*
G01X295460Y86590D02*
X295880D01*
G01X295240Y103180D02*
X294610D01*
G01X294700Y103290D02*
X295330D01*
G01X295430Y103380D02*
X294800D01*
G01X294900Y103490D02*
X295520D01*
G01X295620Y103590D02*
X294990D01*
G01X295180Y103790D02*
X295810D01*
G01X296010Y103990D02*
X295380D01*
G01X295570Y104180D02*
X296200D01*
G01X296100Y104090D02*
X295480D01*
G01X295670Y104290D02*
X296290D01*
G01X296390Y104380D02*
X295760D01*
G01X295860Y104490D02*
X296490D01*
G01X296590Y104590D02*
X295960D01*
G01X296050Y104680D02*
X296680D01*
G01X296780Y104790D02*
X296150D01*
G01X296250Y104880D02*
X296870D01*
G01X296980Y105090D02*
X296440D01*
G01X296970Y105010D02*
X296980Y105090D01*
G01X296960Y104980D02*
X296970Y105010D01*
G01X296350Y104990D02*
X296960D01*
G01X296980Y105580D02*
X296930Y105590D01*
G01X296980Y105090D02*
Y105580D01*
G01X296920Y105590D02*
X296960D01*
G01X296980Y105490D02*
X296830D01*
G01X296730Y105380D02*
X296980D01*
G01Y105290D02*
X296630D01*
G01X296540Y105180D02*
X296980D01*
G01X295910Y103880D02*
X295280D01*
G01X295090Y103680D02*
X295720D01*
G54D16*
G01X121969Y-179426D02*
Y-161926D01*
G01X131139D02*
Y-179426D01*
G01Y-170676D02*
X121969D01*
G01X144054Y-179426D02*
X142744Y-179134D01*
X141434Y-177968D01*
X140560Y-175926D01*
X140124Y-173593D01*
X140560Y-171259D01*
X141434Y-169218D01*
X142744Y-168051D01*
X144054Y-167760D01*
X145364Y-168051D01*
X146674Y-169218D01*
X147547Y-171259D01*
X147766Y-173593D01*
X147547Y-175926D01*
X146674Y-177968D01*
X145364Y-179134D01*
X144054Y-179426D01*
G01X157842D02*
Y-167760D01*
G01Y-170676D02*
X158716Y-169218D01*
X160026Y-168051D01*
X161772Y-167760D01*
X163300Y-168051D01*
X164611Y-169218D01*
X165266Y-171259D01*
Y-179426D01*
G01X175779Y-171551D02*
X182766D01*
X182111Y-169509D01*
X181019Y-168343D01*
X179491Y-167760D01*
X177962Y-168051D01*
X176652Y-168926D01*
X175779Y-170968D01*
X175342Y-172718D01*
Y-174468D01*
X175779Y-176218D01*
X176871Y-177968D01*
X178181Y-179134D01*
X179709Y-179426D01*
X181237Y-178843D01*
X182766Y-177093D01*
G01X191969Y-184676D02*
X193279Y-185259D01*
X195026Y-184676D01*
X196117Y-183510D01*
X196991Y-182051D01*
X198300Y-177385D01*
X201139Y-167760D01*
G01X194152D02*
X198300Y-177385D01*
G01X233300Y-170093D02*
X234174Y-169218D01*
X234829Y-167760D01*
X235266Y-165717D01*
X234829Y-163968D01*
X233956Y-162801D01*
X232427Y-161926D01*
X226532D01*
Y-179426D01*
X233737D01*
X235266Y-178260D01*
X236139Y-176509D01*
X236576Y-174468D01*
X236139Y-172426D01*
X234829Y-170676D01*
X233300Y-170093D01*
X226532D01*
G01X252984Y-179426D02*
Y-167760D01*
G01Y-169801D02*
X252111Y-168635D01*
X250800Y-168051D01*
X249272Y-167760D01*
X247744Y-168343D01*
X246434Y-169509D01*
X245560Y-171259D01*
X245124Y-173593D01*
X245560Y-175926D01*
X246434Y-177676D01*
X247744Y-178843D01*
X249272Y-179426D01*
X250800Y-179134D01*
X252111Y-178260D01*
X252984Y-177093D01*
G01X270484Y-161926D02*
Y-179426D01*
G01Y-176802D02*
X269611Y-178260D01*
X268300Y-179134D01*
X266772Y-179426D01*
X265026Y-178843D01*
X263716Y-177385D01*
X262842Y-175635D01*
X262624Y-173593D01*
X262842Y-171551D01*
X263716Y-169801D01*
X265026Y-168343D01*
X266772Y-167760D01*
X268300Y-168051D01*
X269392Y-168635D01*
X270484Y-169801D01*
G01X280997Y-183801D02*
X282526Y-184968D01*
X284272Y-185259D01*
X285800Y-184968D01*
X287111Y-183510D01*
X287984Y-181468D01*
Y-167760D01*
G01Y-170093D02*
X287111Y-168926D01*
X285800Y-168051D01*
X284272Y-167760D01*
X282526Y-168343D01*
X281434Y-169509D01*
X280560Y-171551D01*
X280124Y-173593D01*
X280342Y-175343D01*
X281216Y-177385D01*
X282526Y-178843D01*
X284272Y-179426D01*
X285582Y-179134D01*
X287111Y-177968D01*
X287984Y-176802D01*
G01X298279Y-171551D02*
X305266D01*
X304611Y-169509D01*
X303519Y-168343D01*
X301991Y-167760D01*
X300462Y-168051D01*
X299152Y-168926D01*
X298279Y-170968D01*
X297842Y-172718D01*
Y-174468D01*
X298279Y-176218D01*
X299371Y-177968D01*
X300681Y-179134D01*
X302209Y-179426D01*
X303737Y-178843D01*
X305266Y-177093D01*
G01X315997Y-179426D02*
Y-167760D01*
G01Y-170093D02*
X317089Y-168926D01*
X318181Y-168051D01*
X319709Y-167760D01*
X320800Y-168051D01*
X322111Y-168926D01*
G01X349687Y-179426D02*
Y-161926D01*
X354927D01*
X356674Y-162801D01*
X357984Y-164843D01*
X358421Y-167176D01*
X357984Y-169509D01*
X356892Y-171259D01*
X354927Y-172135D01*
X349687D01*
G01X371554Y-161926D02*
Y-179426D01*
G01X366532Y-161926D02*
X376576D01*
G01X390800Y-170093D02*
X391674Y-169218D01*
X392329Y-167760D01*
X392766Y-165717D01*
X392329Y-163968D01*
X391456Y-162801D01*
X389927Y-161926D01*
X384032D01*
Y-179426D01*
X391237D01*
X392766Y-178260D01*
X393639Y-176509D01*
X394076Y-174468D01*
X393639Y-172426D01*
X392329Y-170676D01*
X390800Y-170093D01*
X384032D01*
G01X208377Y-134426D02*
Y-116926D01*
X214054Y-131509D01*
X219731Y-116926D01*
Y-134426D01*
G01X231554D02*
X230244Y-134134D01*
X228934Y-132968D01*
X228060Y-130926D01*
X227624Y-128593D01*
X228060Y-126259D01*
X228934Y-124218D01*
X230244Y-123051D01*
X231554Y-122760D01*
X232864Y-123051D01*
X234174Y-124218D01*
X235047Y-126259D01*
X235266Y-128593D01*
X235047Y-130926D01*
X234174Y-132968D01*
X232864Y-134134D01*
X231554Y-134426D01*
G01X252984Y-116926D02*
Y-134426D01*
G01Y-131802D02*
X252111Y-133260D01*
X250800Y-134134D01*
X249272Y-134426D01*
X247526Y-133843D01*
X246216Y-132385D01*
X245342Y-130635D01*
X245124Y-128593D01*
X245342Y-126551D01*
X246216Y-124801D01*
X247526Y-123343D01*
X249272Y-122760D01*
X250800Y-123051D01*
X251892Y-123635D01*
X252984Y-124801D01*
G01X263279Y-126551D02*
X270266D01*
X269611Y-124509D01*
X268519Y-123343D01*
X266991Y-122760D01*
X265462Y-123051D01*
X264152Y-123926D01*
X263279Y-125968D01*
X262842Y-127718D01*
Y-129468D01*
X263279Y-131218D01*
X264371Y-132968D01*
X265681Y-134134D01*
X267209Y-134426D01*
X268737Y-133843D01*
X270266Y-132093D01*
G01X284054Y-134426D02*
Y-116926D01*
G01X536554Y-179426D02*
Y-161926D01*
X533934Y-165426D01*
G01Y-179426D02*
X539174D01*
G01X556674D02*
Y-161926D01*
X548595Y-174468D01*
X559513D01*
G01X567406Y-172135D02*
X568934Y-170093D01*
X570244Y-168926D01*
X571991Y-168343D01*
X573519Y-168926D01*
X574611Y-170093D01*
X575484Y-171843D01*
X575702Y-173884D01*
X575484Y-175635D01*
X574611Y-177385D01*
X573300Y-178843D01*
X571772Y-179426D01*
X570026Y-178843D01*
X568497Y-177093D01*
X567624Y-174468D01*
X567406Y-171551D01*
X567842Y-167760D01*
X568497Y-165717D01*
X569589Y-163676D01*
X571117Y-162218D01*
X572646Y-161926D01*
X574174Y-162509D01*
X575266Y-163968D01*
G01X584906Y-164843D02*
X586216Y-163093D01*
X587744Y-162218D01*
X589491Y-161926D01*
X591674Y-162509D01*
X593202Y-163968D01*
X593639Y-165717D01*
X593421Y-167468D01*
X592547Y-168926D01*
X588181Y-171843D01*
X586216Y-173884D01*
X584906Y-176802D01*
X584469Y-179426D01*
X593639D01*
G01X602842Y-177385D02*
X604371Y-178843D01*
X606117Y-179426D01*
X607864Y-178843D01*
X609392Y-177093D01*
X610484Y-174468D01*
X610921Y-171843D01*
Y-168635D01*
X610484Y-166010D01*
X609392Y-163676D01*
X608082Y-162509D01*
X606554Y-161926D01*
X604807Y-162509D01*
X603497Y-163676D01*
X602624Y-165426D01*
X602187Y-167760D01*
X602624Y-169801D01*
X603716Y-171843D01*
X605026Y-173010D01*
X606554Y-173301D01*
X608300Y-172718D01*
X609611Y-171259D01*
X610921Y-168635D01*
G01X523437Y-134426D02*
Y-116926D01*
X528677D01*
X530424Y-117801D01*
X531734Y-119843D01*
X532171Y-122176D01*
X531734Y-124509D01*
X530642Y-126259D01*
X528677Y-127135D01*
X523437D01*
G01X550107Y-118385D02*
X548797Y-117509D01*
X547269Y-116926D01*
X545522D01*
X543557Y-117801D01*
X542029Y-119259D01*
X540937Y-121010D01*
X540064Y-123926D01*
X539845Y-126551D01*
X540282Y-129176D01*
X540937Y-130926D01*
X542247Y-132676D01*
X543776Y-133843D01*
X545304Y-134426D01*
X546832D01*
X548361Y-133843D01*
X549671Y-132968D01*
X550763Y-131802D01*
G01X564550Y-125093D02*
X565424Y-124218D01*
X566079Y-122760D01*
X566516Y-120717D01*
X566079Y-118968D01*
X565206Y-117801D01*
X563677Y-116926D01*
X557782D01*
Y-134426D01*
X564987D01*
X566516Y-133260D01*
X567389Y-131509D01*
X567826Y-129468D01*
X567389Y-127426D01*
X566079Y-125676D01*
X564550Y-125093D01*
X557782D01*
G01X573754Y-140259D02*
X586854D01*
G01X592782Y-134426D02*
Y-116926D01*
X602826Y-134426D01*
Y-116926D01*
G01X615304Y-134426D02*
X613557Y-134134D01*
X612029Y-132968D01*
X610719Y-131218D01*
X609845Y-129176D01*
X609409Y-126843D01*
Y-124509D01*
X609845Y-122176D01*
X610719Y-120134D01*
X612029Y-118385D01*
X613557Y-117218D01*
X615304Y-116926D01*
X617050Y-117218D01*
X618579Y-118385D01*
X619889Y-120134D01*
X620763Y-122176D01*
X621199Y-124509D01*
Y-126843D01*
X620763Y-129176D01*
X619889Y-131218D01*
X618579Y-132968D01*
X617050Y-134134D01*
X615304Y-134426D01*
G01X689104Y-179426D02*
Y-161926D01*
X686484Y-165426D01*
G01Y-179426D02*
X691724D01*
G01X701145D02*
X706604Y-161926D01*
X712063Y-179426D01*
G01X710097Y-173301D02*
X703110D01*
G01X666145Y-116926D02*
X671604Y-134426D01*
X677063Y-116926D01*
G01X693471Y-134426D02*
X684737D01*
Y-116926D01*
X693471D01*
G01X689977Y-125384D02*
X684737D01*
G01X702237Y-134426D02*
Y-116926D01*
X707696D01*
X709442Y-117801D01*
X710534Y-118968D01*
X710971Y-121301D01*
X710534Y-123635D01*
X709224Y-125093D01*
X707696Y-125968D01*
X702237D01*
G01X707696D02*
X710971Y-134426D01*
G01X724104Y-135009D02*
X723667Y-134718D01*
Y-134134D01*
X724104Y-133843D01*
X724541Y-134134D01*
Y-134718D01*
X724104Y-135009D01*
G01X804054Y-161926D02*
Y-179426D01*
G01X799032Y-161926D02*
X809076D01*
G01X816969Y-177093D02*
X818716Y-178551D01*
X820681Y-179426D01*
X822427D01*
X824174Y-178551D01*
X825484Y-177093D01*
X826139Y-175051D01*
X825702Y-173010D01*
X824611Y-171259D01*
X822646Y-170093D01*
X820026Y-169509D01*
X818497Y-168343D01*
X817842Y-166301D01*
X818279Y-164259D01*
X819371Y-162801D01*
X820899Y-161926D01*
X822427D01*
X823956Y-162509D01*
X825266Y-163968D01*
G01X836434Y-161926D02*
X841674D01*
G01X839054D02*
Y-179426D01*
G01X836434D02*
X841674D01*
G01X852187Y-161926D02*
Y-179426D01*
X860921D01*
G01X869251D02*
Y-161926D01*
G01X877547D02*
X869251Y-172718D01*
G01X878857Y-179426D02*
X872962Y-167760D01*
G01X790937Y-116926D02*
Y-134426D01*
X799671D01*
G01X816734D02*
Y-122760D01*
G01Y-124801D02*
X815861Y-123635D01*
X814550Y-123051D01*
X813022Y-122760D01*
X811494Y-123343D01*
X810184Y-124509D01*
X809310Y-126259D01*
X808874Y-128593D01*
X809310Y-130926D01*
X810184Y-132676D01*
X811494Y-133843D01*
X813022Y-134426D01*
X814550Y-134134D01*
X815861Y-133260D01*
X816734Y-132093D01*
G01X825719Y-139676D02*
X827029Y-140259D01*
X828776Y-139676D01*
X829867Y-138510D01*
X830741Y-137051D01*
X832050Y-132385D01*
X834889Y-122760D01*
G01X827902D02*
X832050Y-132385D01*
G01X844529Y-126551D02*
X851516D01*
X850861Y-124509D01*
X849769Y-123343D01*
X848241Y-122760D01*
X846712Y-123051D01*
X845402Y-123926D01*
X844529Y-125968D01*
X844092Y-127718D01*
Y-129468D01*
X844529Y-131218D01*
X845621Y-132968D01*
X846931Y-134134D01*
X848459Y-134426D01*
X849987Y-133843D01*
X851516Y-132093D01*
G01X862247Y-134426D02*
Y-122760D01*
G01Y-125093D02*
X863339Y-123926D01*
X864431Y-123051D01*
X865959Y-122760D01*
X867050Y-123051D01*
X868361Y-123926D01*
G01X879529Y-132385D02*
X880621Y-133551D01*
X882149Y-134426D01*
X883459D01*
X884769Y-133843D01*
X885642Y-132968D01*
X886079Y-131802D01*
X885861Y-130051D01*
X884987Y-129176D01*
X881057Y-127426D01*
X880184Y-125384D01*
X880621Y-123926D01*
X881494Y-123051D01*
X882804Y-122760D01*
X884114Y-123051D01*
X885424Y-123926D01*
G01X924737Y-175926D02*
X925829Y-177676D01*
X927139Y-178843D01*
X928667Y-179426D01*
X930414Y-178843D01*
X931724Y-177676D01*
X933034Y-175926D01*
X933471Y-173593D01*
Y-161926D01*
G01X946604Y-179426D02*
X944857Y-179134D01*
X943329Y-177968D01*
X942019Y-176218D01*
X941145Y-174176D01*
X940709Y-171843D01*
Y-169509D01*
X941145Y-167176D01*
X942019Y-165134D01*
X943329Y-163385D01*
X944857Y-162218D01*
X946604Y-161926D01*
X948350Y-162218D01*
X949879Y-163385D01*
X951189Y-165134D01*
X952063Y-167176D01*
X952499Y-169509D01*
Y-171843D01*
X952063Y-174176D01*
X951189Y-176218D01*
X949879Y-177968D01*
X948350Y-179134D01*
X946604Y-179426D01*
G01X959519Y-177093D02*
X961266Y-178551D01*
X963231Y-179426D01*
X964977D01*
X966724Y-178551D01*
X968034Y-177093D01*
X968689Y-175051D01*
X968252Y-173010D01*
X967161Y-171259D01*
X965196Y-170093D01*
X962576Y-169509D01*
X961047Y-168343D01*
X960392Y-166301D01*
X960829Y-164259D01*
X961921Y-162801D01*
X963449Y-161926D01*
X964977D01*
X966506Y-162509D01*
X967816Y-163968D01*
G01X985971Y-179426D02*
X977237D01*
Y-161926D01*
X985971D01*
G01X982477Y-170384D02*
X977237D01*
G01X994737Y-179426D02*
Y-161926D01*
X999977D01*
X1001724Y-162801D01*
X1003034Y-164843D01*
X1003471Y-167176D01*
X1003034Y-169509D01*
X1001942Y-171259D01*
X999977Y-172135D01*
X994737D01*
G01X1012019Y-179426D02*
Y-161926D01*
G01X1021189D02*
Y-179426D01*
G01Y-170676D02*
X1012019D01*
G01X1047237Y-161926D02*
Y-179426D01*
X1055971D01*
G01X1063645D02*
X1069104Y-161926D01*
X1074563Y-179426D01*
G01X1072597Y-173301D02*
X1065610D01*
G01X1081801Y-161926D02*
Y-174468D01*
X1082674Y-177093D01*
X1084421Y-178843D01*
X1086604Y-179426D01*
X1088787Y-178843D01*
X1090534Y-177093D01*
X1091407Y-174468D01*
Y-161926D01*
G01X941801Y-134426D02*
Y-116926D01*
X946167D01*
X947914Y-117801D01*
X949224Y-118968D01*
X950316Y-120717D01*
X951189Y-122760D01*
X951407Y-125676D01*
X951189Y-128593D01*
X950316Y-130635D01*
X949224Y-132385D01*
X947914Y-133551D01*
X946167Y-134426D01*
X941801D01*
G01X960829Y-126551D02*
X967816D01*
X967161Y-124509D01*
X966069Y-123343D01*
X964541Y-122760D01*
X963012Y-123051D01*
X961702Y-123926D01*
X960829Y-125968D01*
X960392Y-127718D01*
Y-129468D01*
X960829Y-131218D01*
X961921Y-132968D01*
X963231Y-134134D01*
X964759Y-134426D01*
X966287Y-133843D01*
X967816Y-132093D01*
G01X978329Y-132385D02*
X979421Y-133551D01*
X980949Y-134426D01*
X982259D01*
X983569Y-133843D01*
X984442Y-132968D01*
X984879Y-131802D01*
X984661Y-130051D01*
X983787Y-129176D01*
X979857Y-127426D01*
X978984Y-125384D01*
X979421Y-123926D01*
X980294Y-123051D01*
X981604Y-122760D01*
X982914Y-123051D01*
X984224Y-123926D01*
G01X999104Y-122760D02*
Y-134426D01*
G01Y-118093D02*
X998667Y-117801D01*
Y-117218D01*
X999104Y-116926D01*
X999541Y-117218D01*
Y-117801D01*
X999104Y-118093D01*
G01X1013547Y-138801D02*
X1015076Y-139968D01*
X1016822Y-140259D01*
X1018350Y-139968D01*
X1019661Y-138510D01*
X1020534Y-136468D01*
Y-122760D01*
G01Y-125093D02*
X1019661Y-123926D01*
X1018350Y-123051D01*
X1016822Y-122760D01*
X1015076Y-123343D01*
X1013984Y-124509D01*
X1013110Y-126551D01*
X1012674Y-128593D01*
X1012892Y-130343D01*
X1013766Y-132385D01*
X1015076Y-133843D01*
X1016822Y-134426D01*
X1018132Y-134134D01*
X1019661Y-132968D01*
X1020534Y-131802D01*
G01X1030392Y-134426D02*
Y-122760D01*
G01Y-125676D02*
X1031266Y-124218D01*
X1032576Y-123051D01*
X1034322Y-122760D01*
X1035850Y-123051D01*
X1037161Y-124218D01*
X1037816Y-126259D01*
Y-134426D01*
G01X1048329Y-126551D02*
X1055316D01*
X1054661Y-124509D01*
X1053569Y-123343D01*
X1052041Y-122760D01*
X1050512Y-123051D01*
X1049202Y-123926D01*
X1048329Y-125968D01*
X1047892Y-127718D01*
Y-129468D01*
X1048329Y-131218D01*
X1049421Y-132968D01*
X1050731Y-134134D01*
X1052259Y-134426D01*
X1053787Y-133843D01*
X1055316Y-132093D01*
G01X1066047Y-134426D02*
Y-122760D01*
G01Y-125093D02*
X1067139Y-123926D01*
X1068231Y-123051D01*
X1069759Y-122760D01*
X1070850Y-123051D01*
X1072161Y-123926D01*
G01X1112804Y-179426D02*
Y-161926D01*
X1110184Y-165426D01*
G01Y-179426D02*
X1115424D01*
G01X1130304D02*
Y-161926D01*
X1127684Y-165426D01*
G01Y-179426D02*
X1132924D01*
G01X1143874Y-180009D02*
X1151734Y-161926D01*
G01X1161156Y-164843D02*
X1162466Y-163093D01*
X1163994Y-162218D01*
X1165741Y-161926D01*
X1167924Y-162509D01*
X1169452Y-163968D01*
X1169889Y-165717D01*
X1169671Y-167468D01*
X1168797Y-168926D01*
X1164431Y-171843D01*
X1162466Y-173884D01*
X1161156Y-176802D01*
X1160719Y-179426D01*
X1169889D01*
G01X1178001Y-176802D02*
X1179310Y-178260D01*
X1180839Y-179134D01*
X1182804Y-179426D01*
X1184769Y-178843D01*
X1186297Y-177676D01*
X1187389Y-175635D01*
X1187607Y-173301D01*
X1187171Y-170968D01*
X1186079Y-169509D01*
X1184550Y-168343D01*
X1183022Y-168051D01*
X1181494Y-168343D01*
X1179529Y-169509D01*
X1180184Y-161926D01*
X1186079D01*
G01X1196374Y-180009D02*
X1204234Y-161926D01*
G01X1213656Y-164843D02*
X1214966Y-163093D01*
X1216494Y-162218D01*
X1218241Y-161926D01*
X1220424Y-162509D01*
X1221952Y-163968D01*
X1222389Y-165717D01*
X1222171Y-167468D01*
X1221297Y-168926D01*
X1216931Y-171843D01*
X1214966Y-173884D01*
X1213656Y-176802D01*
X1213219Y-179426D01*
X1222389D01*
G01X1235304Y-161926D02*
X1233557Y-162509D01*
X1232247Y-163968D01*
X1231374Y-165717D01*
X1230719Y-168051D01*
X1230501Y-170676D01*
X1230719Y-173301D01*
X1231374Y-175635D01*
X1232247Y-177385D01*
X1233557Y-178843D01*
X1235304Y-179426D01*
X1237050Y-178843D01*
X1238361Y-177385D01*
X1239234Y-175635D01*
X1239889Y-173301D01*
X1240107Y-170676D01*
X1239889Y-168051D01*
X1239234Y-165717D01*
X1238361Y-163968D01*
X1237050Y-162509D01*
X1235304Y-161926D01*
G01X1252804Y-179426D02*
Y-161926D01*
X1250184Y-165426D01*
G01Y-179426D02*
X1255424D01*
G01X1272924D02*
Y-161926D01*
X1264845Y-174468D01*
X1275763D01*
G01X1160501Y-134426D02*
Y-116926D01*
X1164867D01*
X1166614Y-117801D01*
X1167924Y-118968D01*
X1169016Y-120717D01*
X1169889Y-122760D01*
X1170107Y-125676D01*
X1169889Y-128593D01*
X1169016Y-130635D01*
X1167924Y-132385D01*
X1166614Y-133551D01*
X1164867Y-134426D01*
X1160501D01*
G01X1186734D02*
Y-122760D01*
G01Y-124801D02*
X1185861Y-123635D01*
X1184550Y-123051D01*
X1183022Y-122760D01*
X1181494Y-123343D01*
X1180184Y-124509D01*
X1179310Y-126259D01*
X1178874Y-128593D01*
X1179310Y-130926D01*
X1180184Y-132676D01*
X1181494Y-133843D01*
X1183022Y-134426D01*
X1184550Y-134134D01*
X1185861Y-133260D01*
X1186734Y-132093D01*
G01X1200304Y-116926D02*
Y-134426D01*
G01X1197247Y-122760D02*
X1203361D01*
G01X1214529Y-126551D02*
X1221516D01*
X1220861Y-124509D01*
X1219769Y-123343D01*
X1218241Y-122760D01*
X1216712Y-123051D01*
X1215402Y-123926D01*
X1214529Y-125968D01*
X1214092Y-127718D01*
Y-129468D01*
X1214529Y-131218D01*
X1215621Y-132968D01*
X1216931Y-134134D01*
X1218459Y-134426D01*
X1219987Y-133843D01*
X1221516Y-132093D01*
G01X-6750Y307150D02*
Y307983D01*
X-6000D01*
X-5750Y307733D01*
X-5583Y307442D01*
X-5500Y307025D01*
X-5583Y306608D01*
X-5750Y306317D01*
X-6000Y306067D01*
X-6292Y305900D01*
X-6625Y305817D01*
X-6917D01*
X-7167Y305900D01*
X-7458Y306067D01*
X-7708Y306317D01*
X-7875Y306567D01*
X-8000Y306900D01*
Y307192D01*
X-7917Y307525D01*
X-7750Y307775D01*
G01X-5500Y309208D02*
X-8000D01*
Y310792D01*
G01X-6792Y310208D02*
Y309208D01*
G01X-5500Y313100D02*
X-8000D01*
X-7500Y312600D01*
G01X-5500D02*
Y313600D01*
G01X22575Y82000D02*
Y84500D01*
G01X24325D02*
Y82000D01*
G01Y83250D02*
X22575D01*
G01X25633Y82500D02*
X25883Y82208D01*
X26217Y82042D01*
X26592Y82000D01*
X26925Y82042D01*
X27258Y82250D01*
X27467Y82500D01*
X27508Y82750D01*
X27425Y83042D01*
X27133Y83250D01*
X26842Y83333D01*
X26467D01*
G01X26842D02*
X27092Y83458D01*
X27300Y83667D01*
X27383Y83917D01*
X27300Y84167D01*
X27092Y84375D01*
X26717Y84500D01*
X26342Y84458D01*
X25967Y84292D01*
G01X20208Y191767D02*
X20083Y191517D01*
X20000Y191225D01*
Y190892D01*
X20125Y190517D01*
X20333Y190225D01*
X20583Y190017D01*
X21000Y189850D01*
X21375Y189808D01*
X21750Y189892D01*
X22000Y190017D01*
X22250Y190267D01*
X22417Y190558D01*
X22500Y190850D01*
Y191142D01*
X22417Y191433D01*
X22292Y191683D01*
X22125Y191892D01*
G01X22000Y193033D02*
X22292Y193283D01*
X22458Y193617D01*
X22500Y193992D01*
X22458Y194325D01*
X22250Y194658D01*
X22000Y194867D01*
X21750Y194908D01*
X21458Y194825D01*
X21250Y194533D01*
X21167Y194242D01*
Y193867D01*
G01Y194242D02*
X21042Y194492D01*
X20833Y194700D01*
X20583Y194783D01*
X20333Y194700D01*
X20125Y194492D01*
X20000Y194117D01*
X20042Y193742D01*
X20208Y193367D01*
G01X22500Y197550D02*
X20000D01*
X21792Y196008D01*
Y198092D01*
G01X22208Y199442D02*
X22417Y199733D01*
X22500Y200067D01*
X22417Y200400D01*
X22167Y200692D01*
X21792Y200900D01*
X21417Y200983D01*
X20958D01*
X20583Y200900D01*
X20250Y200692D01*
X20083Y200442D01*
X20000Y200150D01*
X20083Y199817D01*
X20250Y199567D01*
X20500Y199400D01*
X20833Y199317D01*
X21125Y199400D01*
X21417Y199608D01*
X21583Y199858D01*
X21625Y200150D01*
X21542Y200483D01*
X21333Y200733D01*
X20958Y200983D01*
G01X15708Y191767D02*
X15583Y191517D01*
X15500Y191225D01*
Y190892D01*
X15625Y190517D01*
X15833Y190225D01*
X16083Y190017D01*
X16500Y189850D01*
X16875Y189808D01*
X17250Y189892D01*
X17500Y190017D01*
X17750Y190267D01*
X17917Y190558D01*
X18000Y190850D01*
Y191142D01*
X17917Y191433D01*
X17792Y191683D01*
X17625Y191892D01*
G01X17500Y193033D02*
X17792Y193283D01*
X17958Y193617D01*
X18000Y193992D01*
X17958Y194325D01*
X17750Y194658D01*
X17500Y194867D01*
X17250Y194908D01*
X16958Y194825D01*
X16750Y194533D01*
X16667Y194242D01*
Y193867D01*
G01Y194242D02*
X16542Y194492D01*
X16333Y194700D01*
X16083Y194783D01*
X15833Y194700D01*
X15625Y194492D01*
X15500Y194117D01*
X15542Y193742D01*
X15708Y193367D01*
G01X18000Y197550D02*
X15500D01*
X17292Y196008D01*
Y198092D01*
G01X18000Y200150D02*
X17958Y200442D01*
X17833Y200775D01*
X17625Y200983D01*
X17333Y201067D01*
X17042Y200983D01*
X16792Y200733D01*
X16667Y200358D01*
Y199942D01*
X16583Y199692D01*
X16375Y199483D01*
X16083Y199400D01*
X15792Y199525D01*
X15583Y199817D01*
X15500Y200150D01*
X15583Y200483D01*
X15792Y200775D01*
X16083Y200900D01*
X16375Y200817D01*
X16583Y200608D01*
X16667Y200358D01*
Y199942D01*
X16792Y199567D01*
X17042Y199317D01*
X17333Y199233D01*
X17625Y199317D01*
X17833Y199525D01*
X17958Y199858D01*
X18000Y200150D01*
G01X32017Y326500D02*
Y329000D01*
X33058D01*
X33392Y328875D01*
X33600Y328708D01*
X33683Y328375D01*
X33600Y328042D01*
X33350Y327833D01*
X33058Y327708D01*
X32017D01*
G01X33058D02*
X33683Y326500D01*
G01X35033Y327000D02*
X35283Y326708D01*
X35617Y326542D01*
X35992Y326500D01*
X36325Y326542D01*
X36658Y326750D01*
X36867Y327000D01*
X36908Y327250D01*
X36825Y327542D01*
X36533Y327750D01*
X36242Y327833D01*
X35867D01*
G01X36242D02*
X36492Y327958D01*
X36700Y328167D01*
X36783Y328417D01*
X36700Y328667D01*
X36492Y328875D01*
X36117Y329000D01*
X35742Y328958D01*
X35367Y328792D01*
G01X39050Y326500D02*
X39342Y326542D01*
X39675Y326667D01*
X39883Y326875D01*
X39967Y327167D01*
X39883Y327458D01*
X39633Y327708D01*
X39258Y327833D01*
X38842D01*
X38592Y327917D01*
X38383Y328125D01*
X38300Y328417D01*
X38425Y328708D01*
X38717Y328917D01*
X39050Y329000D01*
X39383Y328917D01*
X39675Y328708D01*
X39800Y328417D01*
X39717Y328125D01*
X39508Y327917D01*
X39258Y327833D01*
X38842D01*
X38467Y327708D01*
X38217Y327458D01*
X38133Y327167D01*
X38217Y326875D01*
X38425Y326667D01*
X38758Y326542D01*
X39050Y326500D01*
G01X41233Y326875D02*
X41483Y326667D01*
X41775Y326542D01*
X42150Y326500D01*
X42525Y326583D01*
X42817Y326750D01*
X43025Y327042D01*
X43067Y327375D01*
X42983Y327708D01*
X42775Y327917D01*
X42483Y328083D01*
X42192Y328125D01*
X41900Y328083D01*
X41525Y327917D01*
X41650Y329000D01*
X42775D01*
G01X32017Y322500D02*
Y325000D01*
X33058D01*
X33392Y324875D01*
X33600Y324708D01*
X33683Y324375D01*
X33600Y324042D01*
X33350Y323833D01*
X33058Y323708D01*
X32017D01*
G01X33058D02*
X33683Y322500D01*
G01X35033Y323000D02*
X35283Y322708D01*
X35617Y322542D01*
X35992Y322500D01*
X36325Y322542D01*
X36658Y322750D01*
X36867Y323000D01*
X36908Y323250D01*
X36825Y323542D01*
X36533Y323750D01*
X36242Y323833D01*
X35867D01*
G01X36242D02*
X36492Y323958D01*
X36700Y324167D01*
X36783Y324417D01*
X36700Y324667D01*
X36492Y324875D01*
X36117Y325000D01*
X35742Y324958D01*
X35367Y324792D01*
G01X39050Y322500D02*
X39342Y322542D01*
X39675Y322667D01*
X39883Y322875D01*
X39967Y323167D01*
X39883Y323458D01*
X39633Y323708D01*
X39258Y323833D01*
X38842D01*
X38592Y323917D01*
X38383Y324125D01*
X38300Y324417D01*
X38425Y324708D01*
X38717Y324917D01*
X39050Y325000D01*
X39383Y324917D01*
X39675Y324708D01*
X39800Y324417D01*
X39717Y324125D01*
X39508Y323917D01*
X39258Y323833D01*
X38842D01*
X38467Y323708D01*
X38217Y323458D01*
X38133Y323167D01*
X38217Y322875D01*
X38425Y322667D01*
X38758Y322542D01*
X39050Y322500D01*
G01X42650D02*
Y325000D01*
X41108Y323208D01*
X43192D01*
G01X33198Y335436D02*
Y331436D01*
X40598D01*
G01X47742Y371502D02*
X46142Y369902D01*
G01X47742Y371502D02*
X46142Y373102D01*
G01Y367502D02*
Y375502D01*
G01D02*
X58042D01*
G01D02*
Y367502D01*
G01D02*
X46142D01*
G01X16013Y373593D02*
Y376093D01*
X17054D01*
X17388Y375968D01*
X17596Y375801D01*
X17679Y375468D01*
X17596Y375135D01*
X17346Y374926D01*
X17054Y374801D01*
X16013D01*
G01X17054D02*
X17679Y373593D01*
G01X19029Y374093D02*
X19279Y373801D01*
X19613Y373635D01*
X19988Y373593D01*
X20321Y373635D01*
X20654Y373843D01*
X20863Y374093D01*
X20904Y374343D01*
X20821Y374635D01*
X20529Y374843D01*
X20238Y374926D01*
X19863D01*
G01X20238D02*
X20488Y375051D01*
X20696Y375260D01*
X20779Y375510D01*
X20696Y375760D01*
X20488Y375968D01*
X20113Y376093D01*
X19738Y376051D01*
X19363Y375885D01*
G01X23046Y373593D02*
X23338Y373635D01*
X23671Y373760D01*
X23879Y373968D01*
X23963Y374260D01*
X23879Y374551D01*
X23629Y374801D01*
X23254Y374926D01*
X22838D01*
X22588Y375010D01*
X22379Y375218D01*
X22296Y375510D01*
X22421Y375801D01*
X22713Y376010D01*
X23046Y376093D01*
X23379Y376010D01*
X23671Y375801D01*
X23796Y375510D01*
X23713Y375218D01*
X23504Y375010D01*
X23254Y374926D01*
X22838D01*
X22463Y374801D01*
X22213Y374551D01*
X22129Y374260D01*
X22213Y373968D01*
X22421Y373760D01*
X22754Y373635D01*
X23046Y373593D01*
G01X26146D02*
X26438Y373635D01*
X26771Y373760D01*
X26979Y373968D01*
X27063Y374260D01*
X26979Y374551D01*
X26729Y374801D01*
X26354Y374926D01*
X25938D01*
X25688Y375010D01*
X25479Y375218D01*
X25396Y375510D01*
X25521Y375801D01*
X25813Y376010D01*
X26146Y376093D01*
X26479Y376010D01*
X26771Y375801D01*
X26896Y375510D01*
X26813Y375218D01*
X26604Y375010D01*
X26354Y374926D01*
X25938D01*
X25563Y374801D01*
X25313Y374551D01*
X25229Y374260D01*
X25313Y373968D01*
X25521Y373760D01*
X25854Y373635D01*
X26146Y373593D01*
G01X28108Y376132D02*
Y372132D01*
X35508D01*
G01X15627Y366557D02*
Y369057D01*
X16668D01*
X17002Y368932D01*
X17210Y368765D01*
X17293Y368432D01*
X17210Y368099D01*
X16960Y367890D01*
X16668Y367765D01*
X15627D01*
G01X16668D02*
X17293Y366557D01*
G01X18643Y367057D02*
X18893Y366765D01*
X19227Y366599D01*
X19602Y366557D01*
X19935Y366599D01*
X20268Y366807D01*
X20477Y367057D01*
X20518Y367307D01*
X20435Y367599D01*
X20143Y367807D01*
X19852Y367890D01*
X19477D01*
G01X19852D02*
X20102Y368015D01*
X20310Y368224D01*
X20393Y368474D01*
X20310Y368724D01*
X20102Y368932D01*
X19727Y369057D01*
X19352Y369015D01*
X18977Y368849D01*
G01X22660Y366557D02*
X22952Y366599D01*
X23285Y366724D01*
X23493Y366932D01*
X23577Y367224D01*
X23493Y367515D01*
X23243Y367765D01*
X22868Y367890D01*
X22452D01*
X22202Y367974D01*
X21993Y368182D01*
X21910Y368474D01*
X22035Y368765D01*
X22327Y368974D01*
X22660Y369057D01*
X22993Y368974D01*
X23285Y368765D01*
X23410Y368474D01*
X23327Y368182D01*
X23118Y367974D01*
X22868Y367890D01*
X22452D01*
X22077Y367765D01*
X21827Y367515D01*
X21743Y367224D01*
X21827Y366932D01*
X22035Y366724D01*
X22368Y366599D01*
X22660Y366557D01*
G01X25052Y366849D02*
X25343Y366640D01*
X25677Y366557D01*
X26010Y366640D01*
X26302Y366890D01*
X26510Y367265D01*
X26593Y367640D01*
Y368099D01*
X26510Y368474D01*
X26302Y368807D01*
X26052Y368974D01*
X25760Y369057D01*
X25427Y368974D01*
X25177Y368807D01*
X25010Y368557D01*
X24927Y368224D01*
X25010Y367932D01*
X25218Y367640D01*
X25468Y367474D01*
X25760Y367432D01*
X26093Y367515D01*
X26343Y367724D01*
X26593Y368099D01*
G01X28108Y370932D02*
Y366932D01*
X35508D01*
G01X35441Y348545D02*
X32941D01*
Y349586D01*
X33066Y349920D01*
X33233Y350128D01*
X33566Y350211D01*
X33899Y350128D01*
X34108Y349878D01*
X34233Y349586D01*
Y348545D01*
G01Y349586D02*
X35441Y350211D01*
G01Y352978D02*
X32941D01*
X34733Y351436D01*
Y353520D01*
G01X35441Y355578D02*
X35399Y355870D01*
X35274Y356203D01*
X35066Y356411D01*
X34774Y356495D01*
X34483Y356411D01*
X34233Y356161D01*
X34108Y355786D01*
Y355370D01*
X34024Y355120D01*
X33816Y354911D01*
X33524Y354828D01*
X33233Y354953D01*
X33024Y355245D01*
X32941Y355578D01*
X33024Y355911D01*
X33233Y356203D01*
X33524Y356328D01*
X33816Y356245D01*
X34024Y356036D01*
X34108Y355786D01*
Y355370D01*
X34233Y354995D01*
X34483Y354745D01*
X34774Y354661D01*
X35066Y354745D01*
X35274Y354953D01*
X35399Y355286D01*
X35441Y355578D01*
G01Y359178D02*
X32941D01*
X34733Y357636D01*
Y359720D01*
G01X45072Y371247D02*
X41072D01*
Y363847D01*
G01X34726Y382721D02*
X32226D01*
Y383762D01*
X32351Y384096D01*
X32518Y384304D01*
X32851Y384387D01*
X33184Y384304D01*
X33393Y384054D01*
X33518Y383762D01*
Y382721D01*
G01Y383762D02*
X34726Y384387D01*
G01Y387154D02*
X32226D01*
X34018Y385612D01*
Y387696D01*
G01X34726Y389754D02*
X34684Y390046D01*
X34559Y390379D01*
X34351Y390587D01*
X34059Y390671D01*
X33768Y390587D01*
X33518Y390337D01*
X33393Y389962D01*
Y389546D01*
X33309Y389296D01*
X33101Y389087D01*
X32809Y389004D01*
X32518Y389129D01*
X32309Y389421D01*
X32226Y389754D01*
X32309Y390087D01*
X32518Y390379D01*
X32809Y390504D01*
X33101Y390421D01*
X33309Y390212D01*
X33393Y389962D01*
Y389546D01*
X33518Y389171D01*
X33768Y388921D01*
X34059Y388837D01*
X34351Y388921D01*
X34559Y389129D01*
X34684Y389462D01*
X34726Y389754D01*
G01X33684Y392062D02*
X33393Y392354D01*
X33226Y392604D01*
X33143Y392937D01*
X33226Y393229D01*
X33393Y393437D01*
X33643Y393604D01*
X33934Y393646D01*
X34184Y393604D01*
X34434Y393437D01*
X34643Y393187D01*
X34726Y392896D01*
X34643Y392562D01*
X34393Y392271D01*
X34018Y392104D01*
X33601Y392062D01*
X33059Y392146D01*
X32768Y392271D01*
X32476Y392479D01*
X32268Y392771D01*
X32226Y393062D01*
X32309Y393354D01*
X32518Y393562D01*
G01X45159Y379285D02*
X41159D01*
Y371885D01*
G01X33198Y339936D02*
Y335936D01*
X40598D01*
G01X57352Y392774D02*
X53352D01*
Y385374D01*
G01X59000Y334517D02*
X56500D01*
Y335558D01*
X56625Y335892D01*
X56792Y336100D01*
X57125Y336183D01*
X57458Y336100D01*
X57667Y335850D01*
X57792Y335558D01*
Y334517D01*
G01Y335558D02*
X59000Y336183D01*
G01X58500Y337533D02*
X58792Y337783D01*
X58958Y338117D01*
X59000Y338492D01*
X58958Y338825D01*
X58750Y339158D01*
X58500Y339367D01*
X58250Y339408D01*
X57958Y339325D01*
X57750Y339033D01*
X57667Y338742D01*
Y338367D01*
G01Y338742D02*
X57542Y338992D01*
X57333Y339200D01*
X57083Y339283D01*
X56833Y339200D01*
X56625Y338992D01*
X56500Y338617D01*
X56542Y338242D01*
X56708Y337867D01*
G01X57958Y340758D02*
X57667Y341050D01*
X57500Y341300D01*
X57417Y341633D01*
X57500Y341925D01*
X57667Y342133D01*
X57917Y342300D01*
X58208Y342342D01*
X58458Y342300D01*
X58708Y342133D01*
X58917Y341883D01*
X59000Y341592D01*
X58917Y341258D01*
X58667Y340967D01*
X58292Y340800D01*
X57875Y340758D01*
X57333Y340842D01*
X57042Y340967D01*
X56750Y341175D01*
X56542Y341467D01*
X56500Y341758D01*
X56583Y342050D01*
X56792Y342258D01*
G01X58708Y343942D02*
X58917Y344233D01*
X59000Y344567D01*
X58917Y344900D01*
X58667Y345192D01*
X58292Y345400D01*
X57917Y345483D01*
X57458D01*
X57083Y345400D01*
X56750Y345192D01*
X56583Y344942D01*
X56500Y344650D01*
X56583Y344317D01*
X56750Y344067D01*
X57000Y343900D01*
X57333Y343817D01*
X57625Y343900D01*
X57917Y344108D01*
X58083Y344358D01*
X58125Y344650D01*
X58042Y344983D01*
X57833Y345233D01*
X57458Y345483D01*
G01X55398Y350460D02*
X59398D01*
Y357860D01*
G01X62052Y392692D02*
X58052D01*
Y385292D01*
G01X49500Y334517D02*
X47000D01*
Y335558D01*
X47125Y335892D01*
X47292Y336100D01*
X47625Y336183D01*
X47958Y336100D01*
X48167Y335850D01*
X48292Y335558D01*
Y334517D01*
G01Y335558D02*
X49500Y336183D01*
G01X49000Y337533D02*
X49292Y337783D01*
X49458Y338117D01*
X49500Y338492D01*
X49458Y338825D01*
X49250Y339158D01*
X49000Y339367D01*
X48750Y339408D01*
X48458Y339325D01*
X48250Y339033D01*
X48167Y338742D01*
Y338367D01*
G01Y338742D02*
X48042Y338992D01*
X47833Y339200D01*
X47583Y339283D01*
X47333Y339200D01*
X47125Y338992D01*
X47000Y338617D01*
X47042Y338242D01*
X47208Y337867D01*
G01X49500Y342050D02*
X47000D01*
X48792Y340508D01*
Y342592D01*
G01X49000Y343733D02*
X49292Y343983D01*
X49458Y344317D01*
X49500Y344692D01*
X49458Y345025D01*
X49250Y345358D01*
X49000Y345567D01*
X48750Y345608D01*
X48458Y345525D01*
X48250Y345233D01*
X48167Y344942D01*
Y344567D01*
G01Y344942D02*
X48042Y345192D01*
X47833Y345400D01*
X47583Y345483D01*
X47333Y345400D01*
X47125Y345192D01*
X47000Y344817D01*
X47042Y344442D01*
X47208Y344067D01*
G01X46325Y350450D02*
X50325D01*
Y357850D01*
G01X54500Y334517D02*
X52000D01*
Y335558D01*
X52125Y335892D01*
X52292Y336100D01*
X52625Y336183D01*
X52958Y336100D01*
X53167Y335850D01*
X53292Y335558D01*
Y334517D01*
G01Y335558D02*
X54500Y336183D01*
G01X54000Y337533D02*
X54292Y337783D01*
X54458Y338117D01*
X54500Y338492D01*
X54458Y338825D01*
X54250Y339158D01*
X54000Y339367D01*
X53750Y339408D01*
X53458Y339325D01*
X53250Y339033D01*
X53167Y338742D01*
Y338367D01*
G01Y338742D02*
X53042Y338992D01*
X52833Y339200D01*
X52583Y339283D01*
X52333Y339200D01*
X52125Y338992D01*
X52000Y338617D01*
X52042Y338242D01*
X52208Y337867D01*
G01X54500Y342050D02*
X52000D01*
X53792Y340508D01*
Y342592D01*
G01X52417Y343858D02*
X52167Y344108D01*
X52042Y344400D01*
X52000Y344733D01*
X52083Y345150D01*
X52292Y345442D01*
X52542Y345525D01*
X52792Y345483D01*
X53000Y345317D01*
X53417Y344483D01*
X53708Y344108D01*
X54125Y343858D01*
X54500Y343775D01*
Y345525D01*
G01X50705Y350395D02*
X54705D01*
Y357795D01*
G01X53094Y392725D02*
X49094D01*
Y385325D01*
G01X28929Y350277D02*
X28804Y350027D01*
X28721Y349735D01*
Y349402D01*
X28846Y349027D01*
X29054Y348735D01*
X29304Y348527D01*
X29721Y348360D01*
X30096Y348318D01*
X30471Y348402D01*
X30721Y348527D01*
X30971Y348777D01*
X31138Y349068D01*
X31221Y349360D01*
Y349652D01*
X31138Y349943D01*
X31013Y350193D01*
X30846Y350402D01*
G01X30721Y351543D02*
X31013Y351793D01*
X31179Y352127D01*
X31221Y352502D01*
X31179Y352835D01*
X30971Y353168D01*
X30721Y353377D01*
X30471Y353418D01*
X30179Y353335D01*
X29971Y353043D01*
X29888Y352752D01*
Y352377D01*
G01Y352752D02*
X29763Y353002D01*
X29554Y353210D01*
X29304Y353293D01*
X29054Y353210D01*
X28846Y353002D01*
X28721Y352627D01*
X28763Y352252D01*
X28929Y351877D01*
G01X30846Y354643D02*
X31054Y354893D01*
X31179Y355185D01*
X31221Y355560D01*
X31138Y355935D01*
X30971Y356227D01*
X30679Y356435D01*
X30346Y356477D01*
X30013Y356393D01*
X29804Y356185D01*
X29638Y355893D01*
X29596Y355602D01*
X29638Y355310D01*
X29804Y354935D01*
X28721Y355060D01*
Y356185D01*
G01X31221Y358660D02*
X31179Y358952D01*
X31054Y359285D01*
X30846Y359493D01*
X30554Y359577D01*
X30263Y359493D01*
X30013Y359243D01*
X29888Y358868D01*
Y358452D01*
X29804Y358202D01*
X29596Y357993D01*
X29304Y357910D01*
X29013Y358035D01*
X28804Y358327D01*
X28721Y358660D01*
X28804Y358993D01*
X29013Y359285D01*
X29304Y359410D01*
X29596Y359327D01*
X29804Y359118D01*
X29888Y358868D01*
Y358452D01*
X30013Y358077D01*
X30263Y357827D01*
X30554Y357743D01*
X30846Y357827D01*
X31054Y358035D01*
X31179Y358368D01*
X31221Y358660D01*
G01X28208Y384767D02*
X28083Y384517D01*
X28000Y384225D01*
Y383892D01*
X28125Y383517D01*
X28333Y383225D01*
X28583Y383017D01*
X29000Y382850D01*
X29375Y382808D01*
X29750Y382892D01*
X30000Y383017D01*
X30250Y383267D01*
X30417Y383558D01*
X30500Y383850D01*
Y384142D01*
X30417Y384433D01*
X30292Y384683D01*
X30125Y384892D01*
G01X30000Y386033D02*
X30292Y386283D01*
X30458Y386617D01*
X30500Y386992D01*
X30458Y387325D01*
X30250Y387658D01*
X30000Y387867D01*
X29750Y387908D01*
X29458Y387825D01*
X29250Y387533D01*
X29167Y387242D01*
Y386867D01*
G01Y387242D02*
X29042Y387492D01*
X28833Y387700D01*
X28583Y387783D01*
X28333Y387700D01*
X28125Y387492D01*
X28000Y387117D01*
X28042Y386742D01*
X28208Y386367D01*
G01X30125Y389133D02*
X30333Y389383D01*
X30458Y389675D01*
X30500Y390050D01*
X30417Y390425D01*
X30250Y390717D01*
X29958Y390925D01*
X29625Y390967D01*
X29292Y390883D01*
X29083Y390675D01*
X28917Y390383D01*
X28875Y390092D01*
X28917Y389800D01*
X29083Y389425D01*
X28000Y389550D01*
Y390675D01*
G01X30500Y393067D02*
X29958Y393150D01*
X29500Y393275D01*
X29083Y393442D01*
X28625Y393650D01*
X28000Y393983D01*
Y392317D01*
G01X20575Y438000D02*
Y440500D01*
G01X22325D02*
Y438000D01*
G01Y439250D02*
X20575D01*
G01X23758Y440083D02*
X24008Y440333D01*
X24300Y440458D01*
X24633Y440500D01*
X25050Y440417D01*
X25342Y440208D01*
X25425Y439958D01*
X25383Y439708D01*
X25217Y439500D01*
X24383Y439083D01*
X24008Y438792D01*
X23758Y438375D01*
X23675Y438000D01*
X25425D01*
G01X64500Y398517D02*
X62000D01*
Y399558D01*
X62125Y399892D01*
X62292Y400100D01*
X62625Y400183D01*
X62958Y400100D01*
X63167Y399850D01*
X63292Y399558D01*
Y398517D01*
G01Y399558D02*
X64500Y400183D01*
G01X64000Y401533D02*
X64292Y401783D01*
X64458Y402117D01*
X64500Y402492D01*
X64458Y402825D01*
X64250Y403158D01*
X64000Y403367D01*
X63750Y403408D01*
X63458Y403325D01*
X63250Y403033D01*
X63167Y402742D01*
Y402367D01*
G01Y402742D02*
X63042Y402992D01*
X62833Y403200D01*
X62583Y403283D01*
X62333Y403200D01*
X62125Y402992D01*
X62000Y402617D01*
X62042Y402242D01*
X62208Y401867D01*
G01X64500Y405467D02*
X63958Y405550D01*
X63500Y405675D01*
X63083Y405842D01*
X62625Y406050D01*
X62000Y406383D01*
Y404717D01*
G01Y408650D02*
X62083Y408317D01*
X62292Y408067D01*
X62542Y407900D01*
X62875Y407775D01*
X63250Y407733D01*
X63625Y407775D01*
X63958Y407900D01*
X64208Y408067D01*
X64417Y408317D01*
X64500Y408650D01*
X64417Y408983D01*
X64208Y409233D01*
X63958Y409400D01*
X63625Y409525D01*
X63250Y409567D01*
X62875Y409525D01*
X62542Y409400D01*
X62292Y409233D01*
X62083Y408983D01*
X62000Y408650D01*
G01X60500Y398517D02*
X58000D01*
Y399558D01*
X58125Y399892D01*
X58292Y400100D01*
X58625Y400183D01*
X58958Y400100D01*
X59167Y399850D01*
X59292Y399558D01*
Y398517D01*
G01Y399558D02*
X60500Y400183D01*
G01X60000Y401533D02*
X60292Y401783D01*
X60458Y402117D01*
X60500Y402492D01*
X60458Y402825D01*
X60250Y403158D01*
X60000Y403367D01*
X59750Y403408D01*
X59458Y403325D01*
X59250Y403033D01*
X59167Y402742D01*
Y402367D01*
G01Y402742D02*
X59042Y402992D01*
X58833Y403200D01*
X58583Y403283D01*
X58333Y403200D01*
X58125Y402992D01*
X58000Y402617D01*
X58042Y402242D01*
X58208Y401867D01*
G01X60500Y406050D02*
X58000D01*
X59792Y404508D01*
Y406592D01*
G01X60500Y409150D02*
X58000D01*
X59792Y407608D01*
Y409692D01*
G01X54208Y400267D02*
X54083Y400017D01*
X54000Y399725D01*
Y399392D01*
X54125Y399017D01*
X54333Y398725D01*
X54583Y398517D01*
X55000Y398350D01*
X55375Y398308D01*
X55750Y398392D01*
X56000Y398517D01*
X56250Y398767D01*
X56417Y399058D01*
X56500Y399350D01*
Y399642D01*
X56417Y399933D01*
X56292Y400183D01*
X56125Y400392D01*
G01X56000Y401533D02*
X56292Y401783D01*
X56458Y402117D01*
X56500Y402492D01*
X56458Y402825D01*
X56250Y403158D01*
X56000Y403367D01*
X55750Y403408D01*
X55458Y403325D01*
X55250Y403033D01*
X55167Y402742D01*
Y402367D01*
G01Y402742D02*
X55042Y402992D01*
X54833Y403200D01*
X54583Y403283D01*
X54333Y403200D01*
X54125Y402992D01*
X54000Y402617D01*
X54042Y402242D01*
X54208Y401867D01*
G01X56500Y406050D02*
X54000D01*
X55792Y404508D01*
Y406592D01*
G01X56500Y409150D02*
X54000D01*
X55792Y407608D01*
Y409692D01*
G01X50208Y400267D02*
X50083Y400017D01*
X50000Y399725D01*
Y399392D01*
X50125Y399017D01*
X50333Y398725D01*
X50583Y398517D01*
X51000Y398350D01*
X51375Y398308D01*
X51750Y398392D01*
X52000Y398517D01*
X52250Y398767D01*
X52417Y399058D01*
X52500Y399350D01*
Y399642D01*
X52417Y399933D01*
X52292Y400183D01*
X52125Y400392D01*
G01X52000Y401533D02*
X52292Y401783D01*
X52458Y402117D01*
X52500Y402492D01*
X52458Y402825D01*
X52250Y403158D01*
X52000Y403367D01*
X51750Y403408D01*
X51458Y403325D01*
X51250Y403033D01*
X51167Y402742D01*
Y402367D01*
G01Y402742D02*
X51042Y402992D01*
X50833Y403200D01*
X50583Y403283D01*
X50333Y403200D01*
X50125Y402992D01*
X50000Y402617D01*
X50042Y402242D01*
X50208Y401867D01*
G01X52500Y406050D02*
X50000D01*
X51792Y404508D01*
Y406592D01*
G01X52125Y407733D02*
X52333Y407983D01*
X52458Y408275D01*
X52500Y408650D01*
X52417Y409025D01*
X52250Y409317D01*
X51958Y409525D01*
X51625Y409567D01*
X51292Y409483D01*
X51083Y409275D01*
X50917Y408983D01*
X50875Y408692D01*
X50917Y408400D01*
X51083Y408025D01*
X50000Y408150D01*
Y409275D01*
G01X113521Y-18528D02*
Y-14528D01*
X112721Y-15328D01*
G01Y-18528D02*
X114321D01*
G01X114167Y149500D02*
Y159500D01*
X118500Y151167D01*
X122833Y159500D01*
Y149500D01*
G01X124933D02*
X129100Y159500D01*
X133267Y149500D01*
G01X131767Y153000D02*
X126433D01*
G01X136033Y149500D02*
Y159500D01*
X139367D01*
X140700Y159000D01*
X141700Y158333D01*
X142533Y157333D01*
X143200Y156166D01*
X143367Y154500D01*
X143200Y152833D01*
X142533Y151667D01*
X141700Y150666D01*
X140700Y150000D01*
X139367Y149500D01*
X136033D01*
G01X153633D02*
X146967D01*
Y159500D01*
X153633D01*
G01X150967Y154667D02*
X146967D01*
G01X169500Y159500D02*
X173500D01*
G01X171500D02*
Y149500D01*
G01X169500D02*
X173500D01*
G01X178267D02*
Y159500D01*
X185933Y149500D01*
Y159500D01*
G01X203300D02*
Y149500D01*
G01X199467Y159500D02*
X207133D01*
G01X209733Y149500D02*
X213900Y159500D01*
X218067Y149500D01*
G01X216567Y153000D02*
X211233D01*
G01X222500Y159500D02*
X226500D01*
G01X224500D02*
Y149500D01*
G01X222500D02*
X226500D01*
G01X230100Y159500D02*
X232433Y149500D01*
X235100Y159500D01*
X237767Y149500D01*
X240100Y159500D01*
G01X241533Y149500D02*
X245700Y159500D01*
X249867Y149500D01*
G01X248367Y153000D02*
X243033D01*
G01X252467Y149500D02*
Y159500D01*
X260133Y149500D01*
Y159500D01*
G01X120000Y165500D02*
Y175500D01*
X113833Y168333D01*
X122167D01*
G01X128600Y165500D02*
X129767Y165667D01*
X131100Y166167D01*
X131933Y167000D01*
X132267Y168167D01*
X131933Y169333D01*
X130933Y170333D01*
X129433Y170833D01*
X127767D01*
X126767Y171167D01*
X125933Y172000D01*
X125600Y173167D01*
X126100Y174333D01*
X127266Y175167D01*
X128600Y175500D01*
X129933Y175167D01*
X131100Y174333D01*
X131600Y173167D01*
X131267Y172000D01*
X130433Y171167D01*
X129433Y170833D01*
X127767D01*
X126267Y170333D01*
X125267Y169333D01*
X124933Y168167D01*
X125267Y167000D01*
X126100Y166167D01*
X127433Y165667D01*
X128600Y165500D01*
G01X139200Y165167D02*
X138867Y165333D01*
Y165667D01*
X139200Y165833D01*
X139533Y165667D01*
Y165333D01*
X139200Y165167D01*
G01X146633Y169666D02*
X147800Y170833D01*
X148800Y171500D01*
X150133Y171833D01*
X151300Y171500D01*
X152133Y170833D01*
X152800Y169833D01*
X152967Y168667D01*
X152800Y167667D01*
X152133Y166666D01*
X151133Y165833D01*
X149967Y165500D01*
X148633Y165833D01*
X147467Y166833D01*
X146800Y168333D01*
X146633Y170000D01*
X146967Y172166D01*
X147467Y173333D01*
X148300Y174500D01*
X149467Y175333D01*
X150633Y175500D01*
X151800Y175167D01*
X152633Y174333D01*
G01X162400Y165500D02*
Y175500D01*
X156233Y168333D01*
X164567D01*
G01X166000Y175500D02*
X168333Y165500D01*
X171000Y175500D01*
X173667Y165500D01*
X176000Y175500D01*
G01X178433Y173833D02*
X179433Y174833D01*
X180600Y175333D01*
X181933Y175500D01*
X183600Y175167D01*
X184767Y174333D01*
X185100Y173333D01*
X184933Y172333D01*
X184267Y171500D01*
X180933Y169833D01*
X179433Y168667D01*
X178433Y167000D01*
X178100Y165500D01*
X185100D01*
G01X189033Y173833D02*
X190033Y174833D01*
X191200Y175333D01*
X192533Y175500D01*
X194200Y175167D01*
X195367Y174333D01*
X195700Y173333D01*
X195533Y172333D01*
X194867Y171500D01*
X191533Y169833D01*
X190033Y168667D01*
X189033Y167000D01*
X188700Y165500D01*
X195700D01*
G01X202800Y165167D02*
X202467Y165333D01*
Y165667D01*
X202800Y165833D01*
X203133Y165667D01*
Y165333D01*
X202800Y165167D01*
G01X213400Y175500D02*
X212066Y175167D01*
X211067Y174333D01*
X210400Y173333D01*
X209900Y172000D01*
X209733Y170500D01*
X209900Y169000D01*
X210400Y167667D01*
X211067Y166666D01*
X212066Y165833D01*
X213400Y165500D01*
X214733Y165833D01*
X215733Y166666D01*
X216400Y167667D01*
X216900Y169000D01*
X217067Y170500D01*
X216900Y172000D01*
X216400Y173333D01*
X215733Y174333D01*
X214733Y175167D01*
X213400Y175500D01*
G01X224000Y165500D02*
Y175500D01*
X222000Y173500D01*
G01Y165500D02*
X226000D01*
G01X230433D02*
X234600Y175500D01*
X238767Y165500D01*
G01X237267Y169000D02*
X231933D01*
G01X116200Y194167D02*
Y204167D01*
G01X123200D02*
Y194167D01*
G01Y199167D02*
X116200D01*
G01X130300Y194167D02*
X129300Y194334D01*
X128300Y195000D01*
X127633Y196167D01*
X127300Y197500D01*
X127633Y198834D01*
X128300Y200000D01*
X129300Y200667D01*
X130300Y200833D01*
X131300Y200667D01*
X132300Y200000D01*
X132967Y198834D01*
X133133Y197500D01*
X132967Y196167D01*
X132300Y195000D01*
X131300Y194334D01*
X130300Y194167D01*
G01X138067D02*
Y200833D01*
G01Y199167D02*
X138733Y200000D01*
X139733Y200667D01*
X141067Y200833D01*
X142233Y200667D01*
X143233Y200000D01*
X143733Y198834D01*
Y194167D01*
G01X149000Y198667D02*
X154333D01*
X153833Y199834D01*
X153000Y200500D01*
X151833Y200833D01*
X150667Y200667D01*
X149667Y200167D01*
X149000Y199000D01*
X148667Y198000D01*
Y197000D01*
X149000Y196000D01*
X149833Y195000D01*
X150833Y194334D01*
X152000Y194167D01*
X153167Y194500D01*
X154333Y195500D01*
G01X158600Y191167D02*
X159600Y190834D01*
X160933Y191167D01*
X161767Y191834D01*
X162433Y192667D01*
X163433Y195333D01*
X165600Y200833D01*
G01X160267D02*
X163433Y195333D01*
G01X184633Y199500D02*
X185300Y200000D01*
X185800Y200833D01*
X186133Y202000D01*
X185800Y203000D01*
X185133Y203667D01*
X183967Y204167D01*
X179467D01*
Y194167D01*
X184967D01*
X186133Y194834D01*
X186800Y195834D01*
X187133Y197000D01*
X186800Y198167D01*
X185800Y199167D01*
X184633Y199500D01*
X179467D01*
G01X196900Y194167D02*
Y200833D01*
G01Y199667D02*
X196233Y200334D01*
X195233Y200667D01*
X194067Y200833D01*
X192900Y200500D01*
X191900Y199834D01*
X191233Y198834D01*
X190900Y197500D01*
X191233Y196167D01*
X191900Y195167D01*
X192900Y194500D01*
X194067Y194167D01*
X195233Y194334D01*
X196233Y194834D01*
X196900Y195500D01*
G01X207500Y204167D02*
Y194167D01*
G01Y195667D02*
X206833Y194834D01*
X205833Y194334D01*
X204667Y194167D01*
X203333Y194500D01*
X202333Y195333D01*
X201667Y196334D01*
X201500Y197500D01*
X201667Y198667D01*
X202333Y199667D01*
X203333Y200500D01*
X204667Y200833D01*
X205833Y200667D01*
X206667Y200334D01*
X207500Y199667D01*
G01X212767Y191667D02*
X213933Y191000D01*
X215267Y190834D01*
X216433Y191000D01*
X217433Y191834D01*
X218100Y193000D01*
Y200833D01*
G01Y199500D02*
X217433Y200167D01*
X216433Y200667D01*
X215267Y200833D01*
X213933Y200500D01*
X213100Y199834D01*
X212433Y198667D01*
X212100Y197500D01*
X212267Y196500D01*
X212933Y195333D01*
X213933Y194500D01*
X215267Y194167D01*
X216267Y194334D01*
X217433Y195000D01*
X218100Y195667D01*
G01X223200Y198667D02*
X228533D01*
X228033Y199834D01*
X227200Y200500D01*
X226033Y200833D01*
X224867Y200667D01*
X223867Y200167D01*
X223200Y199000D01*
X222867Y198000D01*
Y197000D01*
X223200Y196000D01*
X224033Y195000D01*
X225033Y194334D01*
X226200Y194167D01*
X227367Y194500D01*
X228533Y195500D01*
G01X233967Y194167D02*
Y200833D01*
G01Y199500D02*
X234800Y200167D01*
X235633Y200667D01*
X236800Y200833D01*
X237633Y200667D01*
X238633Y200167D01*
G01X254167Y194167D02*
Y204167D01*
X258167D01*
X259500Y203667D01*
X260500Y202500D01*
X260833Y201167D01*
X260500Y199834D01*
X259667Y198834D01*
X258167Y198333D01*
X254167D01*
G01X268100Y204167D02*
Y194167D01*
G01X264267Y204167D02*
X271933D01*
G01X280033Y199500D02*
X280700Y200000D01*
X281200Y200833D01*
X281533Y202000D01*
X281200Y203000D01*
X280533Y203667D01*
X279367Y204167D01*
X274867D01*
Y194167D01*
X280367D01*
X281533Y194834D01*
X282200Y195834D01*
X282533Y197000D01*
X282200Y198167D01*
X281200Y199167D01*
X280033Y199500D01*
X274867D01*
G01X118500Y179000D02*
Y189000D01*
X116500Y187000D01*
G01Y179000D02*
X120500D01*
G01X131100D02*
Y189000D01*
X124933Y181833D01*
X133267D01*
G01X136533Y183166D02*
X137700Y184333D01*
X138700Y185000D01*
X140033Y185333D01*
X141200Y185000D01*
X142033Y184333D01*
X142700Y183333D01*
X142867Y182167D01*
X142700Y181167D01*
X142033Y180166D01*
X141033Y179333D01*
X139867Y179000D01*
X138533Y179333D01*
X137367Y180333D01*
X136700Y181833D01*
X136533Y183500D01*
X136867Y185666D01*
X137367Y186833D01*
X138200Y188000D01*
X139367Y188833D01*
X140533Y189000D01*
X141700Y188667D01*
X142533Y187833D01*
G01X147133Y187333D02*
X148133Y188333D01*
X149300Y188833D01*
X150633Y189000D01*
X152300Y188667D01*
X153467Y187833D01*
X153800Y186833D01*
X153633Y185833D01*
X152967Y185000D01*
X149633Y183333D01*
X148133Y182167D01*
X147133Y180500D01*
X146800Y179000D01*
X153800D01*
G01X158067Y180166D02*
X159233Y179333D01*
X160567Y179000D01*
X161900Y179333D01*
X163067Y180333D01*
X163900Y181833D01*
X164233Y183333D01*
Y185167D01*
X163900Y186667D01*
X163067Y188000D01*
X162067Y188667D01*
X160900Y189000D01*
X159566Y188667D01*
X158567Y188000D01*
X157900Y187000D01*
X157567Y185666D01*
X157900Y184500D01*
X158733Y183333D01*
X159733Y182666D01*
X160900Y182500D01*
X162233Y182833D01*
X163233Y183667D01*
X164233Y185167D01*
G01X169333Y182333D02*
X173667D01*
G01X182100Y179000D02*
Y189000D01*
X180100Y187000D01*
G01Y179000D02*
X184100D01*
G01X188533D02*
X192700Y189000D01*
X196867Y179000D01*
G01X195367Y182500D02*
X190033D01*
G01X71000Y382483D02*
X72792D01*
X73167Y382650D01*
X73417Y382983D01*
X73500Y383400D01*
X73417Y383817D01*
X73167Y384150D01*
X72792Y384317D01*
X71000D01*
G01X73125Y385583D02*
X73333Y385833D01*
X73458Y386125D01*
X73500Y386500D01*
X73417Y386875D01*
X73250Y387167D01*
X72958Y387375D01*
X72625Y387417D01*
X72292Y387333D01*
X72083Y387125D01*
X71917Y386833D01*
X71875Y386542D01*
X71917Y386250D01*
X72083Y385875D01*
X71000Y386000D01*
Y387125D01*
G01X73500Y389600D02*
X71000D01*
X71500Y389100D01*
G01X73500D02*
Y390100D01*
G01X77808Y362163D02*
Y364663D01*
X78849D01*
X79183Y364538D01*
X79391Y364371D01*
X79474Y364038D01*
X79391Y363705D01*
X79141Y363496D01*
X78849Y363371D01*
X77808D01*
G01X78849D02*
X79474Y362163D01*
G01X82241D02*
Y364663D01*
X80699Y362871D01*
X82783D01*
G01X84841Y362163D02*
X85133Y362205D01*
X85466Y362330D01*
X85674Y362538D01*
X85758Y362830D01*
X85674Y363121D01*
X85424Y363371D01*
X85049Y363496D01*
X84633D01*
X84383Y363580D01*
X84174Y363788D01*
X84091Y364080D01*
X84216Y364371D01*
X84508Y364580D01*
X84841Y364663D01*
X85174Y364580D01*
X85466Y364371D01*
X85591Y364080D01*
X85508Y363788D01*
X85299Y363580D01*
X85049Y363496D01*
X84633D01*
X84258Y363371D01*
X84008Y363121D01*
X83924Y362830D01*
X84008Y362538D01*
X84216Y362330D01*
X84549Y362205D01*
X84841Y362163D01*
G01X87024Y362538D02*
X87274Y362330D01*
X87566Y362205D01*
X87941Y362163D01*
X88316Y362246D01*
X88608Y362413D01*
X88816Y362705D01*
X88858Y363038D01*
X88774Y363371D01*
X88566Y363580D01*
X88274Y363746D01*
X87983Y363788D01*
X87691Y363746D01*
X87316Y363580D01*
X87441Y364663D01*
X88566D01*
G01X71491Y363163D02*
Y367163D01*
X64091D01*
G01X77367Y379736D02*
Y382236D01*
X78408D01*
X78742Y382111D01*
X78950Y381944D01*
X79033Y381611D01*
X78950Y381278D01*
X78700Y381069D01*
X78408Y380944D01*
X77367D01*
G01X78408D02*
X79033Y379736D01*
G01X81800D02*
Y382236D01*
X80258Y380444D01*
X82342D01*
G01X84400Y379736D02*
X84692Y379778D01*
X85025Y379903D01*
X85233Y380111D01*
X85317Y380403D01*
X85233Y380694D01*
X84983Y380944D01*
X84608Y381069D01*
X84192D01*
X83942Y381153D01*
X83733Y381361D01*
X83650Y381653D01*
X83775Y381944D01*
X84067Y382153D01*
X84400Y382236D01*
X84733Y382153D01*
X85025Y381944D01*
X85150Y381653D01*
X85067Y381361D01*
X84858Y381153D01*
X84608Y381069D01*
X84192D01*
X83817Y380944D01*
X83567Y380694D01*
X83483Y380403D01*
X83567Y380111D01*
X83775Y379903D01*
X84108Y379778D01*
X84400Y379736D01*
G01X87417D02*
X87500Y380278D01*
X87625Y380736D01*
X87792Y381153D01*
X88000Y381611D01*
X88333Y382236D01*
X86667D01*
G01X64150Y380236D02*
Y376236D01*
X71550D01*
G01X77364Y375479D02*
Y377979D01*
X78405D01*
X78739Y377854D01*
X78947Y377687D01*
X79030Y377354D01*
X78947Y377021D01*
X78697Y376812D01*
X78405Y376687D01*
X77364D01*
G01X78405D02*
X79030Y375479D01*
G01X81797D02*
Y377979D01*
X80255Y376187D01*
X82339D01*
G01X84397Y375479D02*
X84689Y375521D01*
X85022Y375646D01*
X85230Y375854D01*
X85314Y376146D01*
X85230Y376437D01*
X84980Y376687D01*
X84605Y376812D01*
X84189D01*
X83939Y376896D01*
X83730Y377104D01*
X83647Y377396D01*
X83772Y377687D01*
X84064Y377896D01*
X84397Y377979D01*
X84730Y377896D01*
X85022Y377687D01*
X85147Y377396D01*
X85064Y377104D01*
X84855Y376896D01*
X84605Y376812D01*
X84189D01*
X83814Y376687D01*
X83564Y376437D01*
X83480Y376146D01*
X83564Y375854D01*
X83772Y375646D01*
X84105Y375521D01*
X84397Y375479D01*
G01X87497D02*
Y377979D01*
X86997Y377479D01*
G01Y375479D02*
X87997D01*
G01X64147Y375979D02*
Y371979D01*
X71547D01*
G01X77815Y366470D02*
Y368970D01*
X78856D01*
X79190Y368845D01*
X79398Y368678D01*
X79481Y368345D01*
X79398Y368012D01*
X79148Y367803D01*
X78856Y367678D01*
X77815D01*
G01X78856D02*
X79481Y366470D01*
G01X82248D02*
Y368970D01*
X80706Y367178D01*
X82790D01*
G01X84848Y366470D02*
X85140Y366512D01*
X85473Y366637D01*
X85681Y366845D01*
X85765Y367137D01*
X85681Y367428D01*
X85431Y367678D01*
X85056Y367803D01*
X84640D01*
X84390Y367887D01*
X84181Y368095D01*
X84098Y368387D01*
X84223Y368678D01*
X84515Y368887D01*
X84848Y368970D01*
X85181Y368887D01*
X85473Y368678D01*
X85598Y368387D01*
X85515Y368095D01*
X85306Y367887D01*
X85056Y367803D01*
X84640D01*
X84265Y367678D01*
X84015Y367428D01*
X83931Y367137D01*
X84015Y366845D01*
X84223Y366637D01*
X84556Y366512D01*
X84848Y366470D01*
G01X87948Y368970D02*
X87615Y368887D01*
X87365Y368678D01*
X87198Y368428D01*
X87073Y368095D01*
X87031Y367720D01*
X87073Y367345D01*
X87198Y367012D01*
X87365Y366762D01*
X87615Y366553D01*
X87948Y366470D01*
X88281Y366553D01*
X88531Y366762D01*
X88698Y367012D01*
X88823Y367345D01*
X88865Y367720D01*
X88823Y368095D01*
X88698Y368428D01*
X88531Y368678D01*
X88281Y368887D01*
X87948Y368970D01*
G01X64098Y371470D02*
Y367470D01*
X71498D01*
G01X70900Y396000D02*
Y393500D01*
G01X69942Y396000D02*
X71858D01*
G01X73167Y393500D02*
Y396000D01*
X74167D01*
X74500Y395875D01*
X74750Y395583D01*
X74833Y395250D01*
X74750Y394917D01*
X74542Y394667D01*
X74167Y394542D01*
X73167D01*
G01X76392Y393792D02*
X76683Y393583D01*
X77017Y393500D01*
X77350Y393583D01*
X77642Y393833D01*
X77850Y394208D01*
X77933Y394583D01*
Y395042D01*
X77850Y395417D01*
X77642Y395750D01*
X77392Y395917D01*
X77100Y396000D01*
X76767Y395917D01*
X76517Y395750D01*
X76350Y395500D01*
X76267Y395167D01*
X76350Y394875D01*
X76558Y394583D01*
X76808Y394417D01*
X77100Y394375D01*
X77433Y394458D01*
X77683Y394667D01*
X77933Y395042D01*
G01X68552Y398509D02*
X66052D01*
Y399550D01*
X66177Y399884D01*
X66344Y400092D01*
X66677Y400175D01*
X67010Y400092D01*
X67219Y399842D01*
X67344Y399550D01*
Y398509D01*
G01Y399550D02*
X68552Y400175D01*
G01X68052Y401525D02*
X68344Y401775D01*
X68510Y402109D01*
X68552Y402484D01*
X68510Y402817D01*
X68302Y403150D01*
X68052Y403359D01*
X67802Y403400D01*
X67510Y403317D01*
X67302Y403025D01*
X67219Y402734D01*
Y402359D01*
G01Y402734D02*
X67094Y402984D01*
X66885Y403192D01*
X66635Y403275D01*
X66385Y403192D01*
X66177Y402984D01*
X66052Y402609D01*
X66094Y402234D01*
X66260Y401859D01*
G01X68177Y404625D02*
X68385Y404875D01*
X68510Y405167D01*
X68552Y405542D01*
X68469Y405917D01*
X68302Y406209D01*
X68010Y406417D01*
X67677Y406459D01*
X67344Y406375D01*
X67135Y406167D01*
X66969Y405875D01*
X66927Y405584D01*
X66969Y405292D01*
X67135Y404917D01*
X66052Y405042D01*
Y406167D01*
G01X68052Y407725D02*
X68344Y407975D01*
X68510Y408309D01*
X68552Y408684D01*
X68510Y409017D01*
X68302Y409350D01*
X68052Y409559D01*
X67802Y409600D01*
X67510Y409517D01*
X67302Y409225D01*
X67219Y408934D01*
Y408559D01*
G01Y408934D02*
X67094Y409184D01*
X66885Y409392D01*
X66635Y409475D01*
X66385Y409392D01*
X66177Y409184D01*
X66052Y408809D01*
X66094Y408434D01*
X66260Y408059D01*
G01X175044Y-17728D02*
X175444Y-18195D01*
X175978Y-18461D01*
X176578Y-18528D01*
X177111Y-18461D01*
X177644Y-18128D01*
X177978Y-17728D01*
X178044Y-17328D01*
X177911Y-16861D01*
X177444Y-16528D01*
X176978Y-16395D01*
X176378D01*
G01X176978D02*
X177378Y-16195D01*
X177711Y-15861D01*
X177844Y-15461D01*
X177711Y-15061D01*
X177378Y-14728D01*
X176778Y-14528D01*
X176178Y-14595D01*
X175578Y-14861D01*
G01X143749Y-15195D02*
X144149Y-14795D01*
X144616Y-14595D01*
X145149Y-14528D01*
X145816Y-14661D01*
X146283Y-14995D01*
X146416Y-15395D01*
X146349Y-15795D01*
X146083Y-16128D01*
X144749Y-16795D01*
X144149Y-17261D01*
X143749Y-17928D01*
X143616Y-18528D01*
X146416D01*
G01X208806D02*
Y-14528D01*
X206339Y-17395D01*
X209673D01*
G01X269730Y-16861D02*
X270197Y-16395D01*
X270597Y-16128D01*
X271130Y-15995D01*
X271597Y-16128D01*
X271930Y-16395D01*
X272197Y-16795D01*
X272264Y-17261D01*
X272197Y-17661D01*
X271930Y-18061D01*
X271530Y-18395D01*
X271064Y-18528D01*
X270530Y-18395D01*
X270064Y-17995D01*
X269797Y-17395D01*
X269730Y-16728D01*
X269864Y-15861D01*
X270064Y-15395D01*
X270397Y-14928D01*
X270864Y-14595D01*
X271330Y-14528D01*
X271797Y-14661D01*
X272130Y-14995D01*
G01X238035Y-17928D02*
X238435Y-18261D01*
X238902Y-18461D01*
X239502Y-18528D01*
X240102Y-18395D01*
X240569Y-18128D01*
X240902Y-17661D01*
X240969Y-17128D01*
X240835Y-16595D01*
X240502Y-16261D01*
X240035Y-15995D01*
X239569Y-15928D01*
X239102Y-15995D01*
X238502Y-16261D01*
X238702Y-14528D01*
X240502D01*
G01X276585Y73780D02*
X278835D01*
G01X276585Y67900D02*
Y73780D01*
G01X278835Y67900D02*
X276585D01*
G01X277935Y70935D02*
X276585D01*
G01X282335Y69570D02*
Y73780D01*
G01X282105Y68685D02*
X282335Y69570D01*
G01X281655Y68100D02*
X282105Y68685D01*
G01X281090Y67900D02*
X281655Y68100D01*
G01X280525D02*
X281090Y67900D01*
G01X280075Y68685D02*
X280525Y68100D01*
G01X279850Y69570D02*
X280075Y68685D01*
G01X279850Y73780D02*
Y69570D01*
G01X288300Y67995D02*
X287855Y67900D01*
G01X288700Y68390D02*
X288300Y67995D01*
G01X289035Y68980D02*
X288700Y68390D01*
G01X289265Y69665D02*
X289035Y68980D01*
G01X289375Y70450D02*
X289265Y69665D01*
G01X289375Y71230D02*
Y70450D01*
G01X289265Y72015D02*
X289375Y71230D01*
G01X289035Y72700D02*
X289265Y72015D01*
G01X288700Y73290D02*
X289035Y72700D01*
G01X288300Y73685D02*
X288700Y73290D01*
G01X287855Y73780D02*
X288300Y73685D01*
G01X287405D02*
X287855Y73780D01*
G01X287005Y73290D02*
X287405Y73685D01*
G01X286670Y72700D02*
X287005Y73290D01*
G01X286440Y72015D02*
X286670Y72700D01*
G01X286330Y71230D02*
X286440Y72015D01*
G01X286330Y70450D02*
Y71230D01*
G01X286440Y69665D02*
X286330Y70450D01*
G01X286670Y68980D02*
X286440Y69665D01*
G01X287005Y68390D02*
X286670Y68980D01*
G01X287405Y67995D02*
X287005Y68390D01*
G01X287855Y67900D02*
X287405Y67995D01*
G01X290280Y67900D02*
Y71820D01*
G01X292190Y70640D02*
Y67900D01*
G01X292020Y71330D02*
X292190Y70640D01*
G01X291680Y71720D02*
X292020Y71330D01*
G01X291290Y71820D02*
X291680Y71720D01*
G01X290835D02*
X291290Y71820D01*
G01X290500Y71330D02*
X290835Y71720D01*
G01X290280Y70840D02*
X290500Y71330D01*
G01X309333Y72500D02*
Y77500D01*
X311417D01*
X312083Y77250D01*
X312500Y76917D01*
X312667Y76250D01*
X312500Y75583D01*
X312000Y75167D01*
X311417Y74917D01*
X309333D01*
G01X311417D02*
X312667Y72500D01*
G01X316600D02*
X315933Y72583D01*
X315350Y72917D01*
X314850Y73417D01*
X314517Y74000D01*
X314350Y74667D01*
Y75333D01*
X314517Y76000D01*
X314850Y76583D01*
X315350Y77083D01*
X315933Y77417D01*
X316600Y77500D01*
X317267Y77417D01*
X317850Y77083D01*
X318350Y76583D01*
X318683Y76000D01*
X318850Y75333D01*
Y74667D01*
X318683Y74000D01*
X318350Y73417D01*
X317850Y72917D01*
X317267Y72583D01*
X316600Y72500D01*
G01X320450D02*
Y77500D01*
G01X323950D02*
Y72500D01*
G01Y75000D02*
X320450D01*
G01X326050Y73167D02*
X326717Y72750D01*
X327467Y72500D01*
X328133D01*
X328800Y72750D01*
X329300Y73167D01*
X329550Y73750D01*
X329383Y74333D01*
X328967Y74833D01*
X328217Y75167D01*
X327217Y75333D01*
X326633Y75667D01*
X326383Y76250D01*
X326550Y76833D01*
X326967Y77250D01*
X327550Y77500D01*
X328133D01*
X328717Y77333D01*
X329217Y76917D01*
G01X340333Y75417D02*
X339750Y75750D01*
X339250Y75833D01*
X338583Y75667D01*
X338083Y75333D01*
X337750Y74750D01*
X337667Y74167D01*
X337750Y73583D01*
X338083Y73083D01*
X338583Y72667D01*
X339250Y72500D01*
X339833Y72667D01*
X340333Y73000D01*
G01X344600Y72500D02*
X344100Y72583D01*
X343600Y72917D01*
X343267Y73500D01*
X343100Y74167D01*
X343267Y74833D01*
X343600Y75417D01*
X344100Y75750D01*
X344600Y75833D01*
X345100Y75750D01*
X345600Y75417D01*
X345933Y74833D01*
X346017Y74167D01*
X345933Y73500D01*
X345600Y72917D01*
X345100Y72583D01*
X344600Y72500D01*
G01X347700D02*
Y75833D01*
G01Y74917D02*
X347950Y75333D01*
X348367Y75667D01*
X348950Y75833D01*
X349533Y75667D01*
X349950Y75333D01*
X350200Y74917D01*
Y72500D01*
G01Y74917D02*
X350450Y75333D01*
X350867Y75667D01*
X351450Y75833D01*
X352033Y75667D01*
X352450Y75333D01*
X352700Y74833D01*
Y72500D01*
G01X354300Y70833D02*
Y75833D01*
G01Y75083D02*
X354717Y75500D01*
X355133Y75750D01*
X355800Y75833D01*
X356383Y75750D01*
X356967Y75333D01*
X357217Y74750D01*
X357300Y74167D01*
X357217Y73583D01*
X356967Y73000D01*
X356467Y72667D01*
X355800Y72500D01*
X355217Y72583D01*
X354633Y72833D01*
X354300Y73167D01*
G01X361400Y72500D02*
Y77500D01*
G01X367000Y75833D02*
Y72500D01*
G01Y77167D02*
X366833Y77250D01*
Y77417D01*
X367000Y77500D01*
X367167Y77417D01*
Y77250D01*
X367000Y77167D01*
G01X374100Y72500D02*
Y75833D01*
G01Y75250D02*
X373767Y75583D01*
X373267Y75750D01*
X372683Y75833D01*
X372100Y75667D01*
X371600Y75333D01*
X371267Y74833D01*
X371100Y74167D01*
X371267Y73500D01*
X371600Y73000D01*
X372100Y72667D01*
X372683Y72500D01*
X373267Y72583D01*
X373767Y72833D01*
X374100Y73167D01*
G01X376783Y72500D02*
Y75833D01*
G01Y75000D02*
X377117Y75417D01*
X377617Y75750D01*
X378283Y75833D01*
X378867Y75750D01*
X379367Y75417D01*
X379617Y74833D01*
Y72500D01*
G01X385133Y75417D02*
X384550Y75750D01*
X384050Y75833D01*
X383383Y75667D01*
X382883Y75333D01*
X382550Y74750D01*
X382467Y74167D01*
X382550Y73583D01*
X382883Y73083D01*
X383383Y72667D01*
X384050Y72500D01*
X384633Y72667D01*
X385133Y73000D01*
G01X388150Y74750D02*
X390817D01*
X390567Y75333D01*
X390150Y75667D01*
X389567Y75833D01*
X388983Y75750D01*
X388483Y75500D01*
X388150Y74917D01*
X387983Y74417D01*
Y73917D01*
X388150Y73417D01*
X388567Y72917D01*
X389067Y72583D01*
X389650Y72500D01*
X390233Y72667D01*
X390817Y73167D01*
G01X294615Y67900D02*
Y73780D01*
G01X298445Y68585D02*
X299180Y71820D01*
G01X298105Y67020D02*
X298445Y68585D01*
G01X297885Y66525D02*
X298105Y67020D01*
G01X297600Y66135D02*
X297885Y66525D01*
G01X297150Y65940D02*
X297600Y66135D01*
G01X296810D02*
X297150Y65940D01*
G01X297380Y71820D02*
X298445Y68585D01*
G01X460708Y207767D02*
X460583Y207517D01*
X460500Y207225D01*
Y206892D01*
X460625Y206517D01*
X460833Y206225D01*
X461083Y206017D01*
X461500Y205850D01*
X461875Y205808D01*
X462250Y205892D01*
X462500Y206017D01*
X462750Y206267D01*
X462917Y206558D01*
X463000Y206850D01*
Y207142D01*
X462917Y207433D01*
X462792Y207683D01*
X462625Y207892D01*
G01X462500Y209033D02*
X462792Y209283D01*
X462958Y209617D01*
X463000Y209992D01*
X462958Y210325D01*
X462750Y210658D01*
X462500Y210867D01*
X462250Y210908D01*
X461958Y210825D01*
X461750Y210533D01*
X461667Y210242D01*
Y209867D01*
G01Y210242D02*
X461542Y210492D01*
X461333Y210700D01*
X461083Y210783D01*
X460833Y210700D01*
X460625Y210492D01*
X460500Y210117D01*
X460542Y209742D01*
X460708Y209367D01*
G01X461958Y212258D02*
X461667Y212550D01*
X461500Y212800D01*
X461417Y213133D01*
X461500Y213425D01*
X461667Y213633D01*
X461917Y213800D01*
X462208Y213842D01*
X462458Y213800D01*
X462708Y213633D01*
X462917Y213383D01*
X463000Y213092D01*
X462917Y212758D01*
X462667Y212467D01*
X462292Y212300D01*
X461875Y212258D01*
X461333Y212342D01*
X461042Y212467D01*
X460750Y212675D01*
X460542Y212967D01*
X460500Y213258D01*
X460583Y213550D01*
X460792Y213758D01*
G01X463000Y216150D02*
X460500D01*
X461000Y215650D01*
G01X463000D02*
Y216650D01*
G01X468200Y189500D02*
Y195700D01*
X455800D01*
Y189500D01*
G01Y183500D02*
Y177300D01*
X468200D01*
Y183500D01*
G01X447208Y207767D02*
X447083Y207517D01*
X447000Y207225D01*
Y206892D01*
X447125Y206517D01*
X447333Y206225D01*
X447583Y206017D01*
X448000Y205850D01*
X448375Y205808D01*
X448750Y205892D01*
X449000Y206017D01*
X449250Y206267D01*
X449417Y206558D01*
X449500Y206850D01*
Y207142D01*
X449417Y207433D01*
X449292Y207683D01*
X449125Y207892D01*
G01X449000Y209033D02*
X449292Y209283D01*
X449458Y209617D01*
X449500Y209992D01*
X449458Y210325D01*
X449250Y210658D01*
X449000Y210867D01*
X448750Y210908D01*
X448458Y210825D01*
X448250Y210533D01*
X448167Y210242D01*
Y209867D01*
G01Y210242D02*
X448042Y210492D01*
X447833Y210700D01*
X447583Y210783D01*
X447333Y210700D01*
X447125Y210492D01*
X447000Y210117D01*
X447042Y209742D01*
X447208Y209367D01*
G01X448458Y212258D02*
X448167Y212550D01*
X448000Y212800D01*
X447917Y213133D01*
X448000Y213425D01*
X448167Y213633D01*
X448417Y213800D01*
X448708Y213842D01*
X448958Y213800D01*
X449208Y213633D01*
X449417Y213383D01*
X449500Y213092D01*
X449417Y212758D01*
X449167Y212467D01*
X448792Y212300D01*
X448375Y212258D01*
X447833Y212342D01*
X447542Y212467D01*
X447250Y212675D01*
X447042Y212967D01*
X447000Y213258D01*
X447083Y213550D01*
X447292Y213758D01*
G01X447417Y215358D02*
X447167Y215608D01*
X447042Y215900D01*
X447000Y216233D01*
X447083Y216650D01*
X447292Y216942D01*
X447542Y217025D01*
X447792Y216983D01*
X448000Y216817D01*
X448417Y215983D01*
X448708Y215608D01*
X449125Y215358D01*
X449500Y215275D01*
Y217025D01*
G01X454700Y189500D02*
Y195700D01*
X442300D01*
Y189500D01*
G01Y183500D02*
Y177300D01*
X454700D01*
Y183500D01*
G01X432208Y207767D02*
X432083Y207517D01*
X432000Y207225D01*
Y206892D01*
X432125Y206517D01*
X432333Y206225D01*
X432583Y206017D01*
X433000Y205850D01*
X433375Y205808D01*
X433750Y205892D01*
X434000Y206017D01*
X434250Y206267D01*
X434417Y206558D01*
X434500Y206850D01*
Y207142D01*
X434417Y207433D01*
X434292Y207683D01*
X434125Y207892D01*
G01X434000Y209033D02*
X434292Y209283D01*
X434458Y209617D01*
X434500Y209992D01*
X434458Y210325D01*
X434250Y210658D01*
X434000Y210867D01*
X433750Y210908D01*
X433458Y210825D01*
X433250Y210533D01*
X433167Y210242D01*
Y209867D01*
G01Y210242D02*
X433042Y210492D01*
X432833Y210700D01*
X432583Y210783D01*
X432333Y210700D01*
X432125Y210492D01*
X432000Y210117D01*
X432042Y209742D01*
X432208Y209367D01*
G01X433458Y212258D02*
X433167Y212550D01*
X433000Y212800D01*
X432917Y213133D01*
X433000Y213425D01*
X433167Y213633D01*
X433417Y213800D01*
X433708Y213842D01*
X433958Y213800D01*
X434208Y213633D01*
X434417Y213383D01*
X434500Y213092D01*
X434417Y212758D01*
X434167Y212467D01*
X433792Y212300D01*
X433375Y212258D01*
X432833Y212342D01*
X432542Y212467D01*
X432250Y212675D01*
X432042Y212967D01*
X432000Y213258D01*
X432083Y213550D01*
X432292Y213758D01*
G01X434000Y215233D02*
X434292Y215483D01*
X434458Y215817D01*
X434500Y216192D01*
X434458Y216525D01*
X434250Y216858D01*
X434000Y217067D01*
X433750Y217108D01*
X433458Y217025D01*
X433250Y216733D01*
X433167Y216442D01*
Y216067D01*
G01Y216442D02*
X433042Y216692D01*
X432833Y216900D01*
X432583Y216983D01*
X432333Y216900D01*
X432125Y216692D01*
X432000Y216317D01*
X432042Y215942D01*
X432208Y215567D01*
G01X441200Y189500D02*
Y195700D01*
X428800D01*
Y189500D01*
G01Y183500D02*
Y177300D01*
X441200D01*
Y183500D01*
G01X422708Y207267D02*
X422583Y207017D01*
X422500Y206725D01*
Y206392D01*
X422625Y206017D01*
X422833Y205725D01*
X423083Y205517D01*
X423500Y205350D01*
X423875Y205308D01*
X424250Y205392D01*
X424500Y205517D01*
X424750Y205767D01*
X424917Y206058D01*
X425000Y206350D01*
Y206642D01*
X424917Y206933D01*
X424792Y207183D01*
X424625Y207392D01*
G01X424500Y208533D02*
X424792Y208783D01*
X424958Y209117D01*
X425000Y209492D01*
X424958Y209825D01*
X424750Y210158D01*
X424500Y210367D01*
X424250Y210408D01*
X423958Y210325D01*
X423750Y210033D01*
X423667Y209742D01*
Y209367D01*
G01Y209742D02*
X423542Y209992D01*
X423333Y210200D01*
X423083Y210283D01*
X422833Y210200D01*
X422625Y209992D01*
X422500Y209617D01*
X422542Y209242D01*
X422708Y208867D01*
G01X423958Y211758D02*
X423667Y212050D01*
X423500Y212300D01*
X423417Y212633D01*
X423500Y212925D01*
X423667Y213133D01*
X423917Y213300D01*
X424208Y213342D01*
X424458Y213300D01*
X424708Y213133D01*
X424917Y212883D01*
X425000Y212592D01*
X424917Y212258D01*
X424667Y211967D01*
X424292Y211800D01*
X423875Y211758D01*
X423333Y211842D01*
X423042Y211967D01*
X422750Y212175D01*
X422542Y212467D01*
X422500Y212758D01*
X422583Y213050D01*
X422792Y213258D01*
G01X425000Y216150D02*
X422500D01*
X424292Y214608D01*
Y216692D01*
G01X427700Y189500D02*
Y195700D01*
X415300D01*
Y189500D01*
G01Y183500D02*
Y177300D01*
X427700D01*
Y183500D01*
G01X445209Y456500D02*
Y459000D01*
G01X446959D02*
Y456500D01*
G01Y457750D02*
X445209D01*
G01X449184Y456500D02*
Y459000D01*
X448684Y458500D01*
G01Y456500D02*
X449684D01*
G01X496075Y45000D02*
Y47500D01*
G01X497825D02*
Y45000D01*
G01Y46250D02*
X496075D01*
G01X500550Y45000D02*
Y47500D01*
X499008Y45708D01*
X501092D01*
G01X508900Y217500D02*
Y215000D01*
G01X507942Y217500D02*
X509858D01*
G01X512917Y217292D02*
X512667Y217417D01*
X512375Y217500D01*
X512042D01*
X511667Y217375D01*
X511375Y217167D01*
X511167Y216917D01*
X511000Y216500D01*
X510958Y216125D01*
X511042Y215750D01*
X511167Y215500D01*
X511417Y215250D01*
X511708Y215083D01*
X512000Y215000D01*
X512292D01*
X512583Y215083D01*
X512833Y215208D01*
X513042Y215375D01*
G01X514183D02*
X514433Y215167D01*
X514725Y215042D01*
X515100Y215000D01*
X515475Y215083D01*
X515767Y215250D01*
X515975Y215542D01*
X516017Y215875D01*
X515933Y216208D01*
X515725Y216417D01*
X515433Y216583D01*
X515142Y216625D01*
X514850Y216583D01*
X514475Y216417D01*
X514600Y217500D01*
X515725D01*
G01X503989Y193762D02*
Y204962D01*
G01D02*
X521989D01*
G01X503989Y177762D02*
Y166562D01*
G01D02*
X521989D01*
G01X483900Y217500D02*
Y215000D01*
G01X482942Y217500D02*
X484858D01*
G01X487917Y217292D02*
X487667Y217417D01*
X487375Y217500D01*
X487042D01*
X486667Y217375D01*
X486375Y217167D01*
X486167Y216917D01*
X486000Y216500D01*
X485958Y216125D01*
X486042Y215750D01*
X486167Y215500D01*
X486417Y215250D01*
X486708Y215083D01*
X487000Y215000D01*
X487292D01*
X487583Y215083D01*
X487833Y215208D01*
X488042Y215375D01*
G01X489183Y215500D02*
X489433Y215208D01*
X489767Y215042D01*
X490142Y215000D01*
X490475Y215042D01*
X490808Y215250D01*
X491017Y215500D01*
X491058Y215750D01*
X490975Y216042D01*
X490683Y216250D01*
X490392Y216333D01*
X490017D01*
G01X490392D02*
X490642Y216458D01*
X490850Y216667D01*
X490933Y216917D01*
X490850Y217167D01*
X490642Y217375D01*
X490267Y217500D01*
X489892Y217458D01*
X489517Y217292D01*
G01X478625Y193686D02*
Y204886D01*
G01D02*
X496625D01*
G01D02*
Y193686D01*
G01X478625Y177686D02*
Y166486D01*
G01D02*
X496625D01*
G01D02*
Y177686D01*
G01X471208Y207767D02*
X471083Y207517D01*
X471000Y207225D01*
Y206892D01*
X471125Y206517D01*
X471333Y206225D01*
X471583Y206017D01*
X472000Y205850D01*
X472375Y205808D01*
X472750Y205892D01*
X473000Y206017D01*
X473250Y206267D01*
X473417Y206558D01*
X473500Y206850D01*
Y207142D01*
X473417Y207433D01*
X473292Y207683D01*
X473125Y207892D01*
G01X473000Y209033D02*
X473292Y209283D01*
X473458Y209617D01*
X473500Y209992D01*
X473458Y210325D01*
X473250Y210658D01*
X473000Y210867D01*
X472750Y210908D01*
X472458Y210825D01*
X472250Y210533D01*
X472167Y210242D01*
Y209867D01*
G01Y210242D02*
X472042Y210492D01*
X471833Y210700D01*
X471583Y210783D01*
X471333Y210700D01*
X471125Y210492D01*
X471000Y210117D01*
X471042Y209742D01*
X471208Y209367D01*
G01X473125Y212133D02*
X473333Y212383D01*
X473458Y212675D01*
X473500Y213050D01*
X473417Y213425D01*
X473250Y213717D01*
X472958Y213925D01*
X472625Y213967D01*
X472292Y213883D01*
X472083Y213675D01*
X471917Y213383D01*
X471875Y213092D01*
X471917Y212800D01*
X472083Y212425D01*
X471000Y212550D01*
Y213675D01*
G01X473125Y215233D02*
X473333Y215483D01*
X473458Y215775D01*
X473500Y216150D01*
X473417Y216525D01*
X473250Y216817D01*
X472958Y217025D01*
X472625Y217067D01*
X472292Y216983D01*
X472083Y216775D01*
X471917Y216483D01*
X471875Y216192D01*
X471917Y215900D01*
X472083Y215525D01*
X471000Y215650D01*
Y216775D01*
G01X519517Y263000D02*
Y265500D01*
X520558D01*
X520892Y265375D01*
X521100Y265208D01*
X521183Y264875D01*
X521100Y264542D01*
X520850Y264333D01*
X520558Y264208D01*
X519517D01*
G01X520558D02*
X521183Y263000D01*
G01X522533Y263500D02*
X522783Y263208D01*
X523117Y263042D01*
X523492Y263000D01*
X523825Y263042D01*
X524158Y263250D01*
X524367Y263500D01*
X524408Y263750D01*
X524325Y264042D01*
X524033Y264250D01*
X523742Y264333D01*
X523367D01*
G01X523742D02*
X523992Y264458D01*
X524200Y264667D01*
X524283Y264917D01*
X524200Y265167D01*
X523992Y265375D01*
X523617Y265500D01*
X523242Y265458D01*
X522867Y265292D01*
G01X526550Y263000D02*
X526842Y263042D01*
X527175Y263167D01*
X527383Y263375D01*
X527467Y263667D01*
X527383Y263958D01*
X527133Y264208D01*
X526758Y264333D01*
X526342D01*
X526092Y264417D01*
X525883Y264625D01*
X525800Y264917D01*
X525925Y265208D01*
X526217Y265417D01*
X526550Y265500D01*
X526883Y265417D01*
X527175Y265208D01*
X527300Y264917D01*
X527217Y264625D01*
X527008Y264417D01*
X526758Y264333D01*
X526342D01*
X525967Y264208D01*
X525717Y263958D01*
X525633Y263667D01*
X525717Y263375D01*
X525925Y263167D01*
X526258Y263042D01*
X526550Y263000D01*
G01X529567D02*
X529650Y263542D01*
X529775Y264000D01*
X529942Y264417D01*
X530150Y264875D01*
X530483Y265500D01*
X528817D01*
G01X519517Y267500D02*
Y270000D01*
X520558D01*
X520892Y269875D01*
X521100Y269708D01*
X521183Y269375D01*
X521100Y269042D01*
X520850Y268833D01*
X520558Y268708D01*
X519517D01*
G01X520558D02*
X521183Y267500D01*
G01X522533Y268000D02*
X522783Y267708D01*
X523117Y267542D01*
X523492Y267500D01*
X523825Y267542D01*
X524158Y267750D01*
X524367Y268000D01*
X524408Y268250D01*
X524325Y268542D01*
X524033Y268750D01*
X523742Y268833D01*
X523367D01*
G01X523742D02*
X523992Y268958D01*
X524200Y269167D01*
X524283Y269417D01*
X524200Y269667D01*
X523992Y269875D01*
X523617Y270000D01*
X523242Y269958D01*
X522867Y269792D01*
G01X526550Y267500D02*
X526842Y267542D01*
X527175Y267667D01*
X527383Y267875D01*
X527467Y268167D01*
X527383Y268458D01*
X527133Y268708D01*
X526758Y268833D01*
X526342D01*
X526092Y268917D01*
X525883Y269125D01*
X525800Y269417D01*
X525925Y269708D01*
X526217Y269917D01*
X526550Y270000D01*
X526883Y269917D01*
X527175Y269708D01*
X527300Y269417D01*
X527217Y269125D01*
X527008Y268917D01*
X526758Y268833D01*
X526342D01*
X525967Y268708D01*
X525717Y268458D01*
X525633Y268167D01*
X525717Y267875D01*
X525925Y267667D01*
X526258Y267542D01*
X526550Y267500D01*
G01X528858Y268542D02*
X529150Y268833D01*
X529400Y269000D01*
X529733Y269083D01*
X530025Y269000D01*
X530233Y268833D01*
X530400Y268583D01*
X530442Y268292D01*
X530400Y268042D01*
X530233Y267792D01*
X529983Y267583D01*
X529692Y267500D01*
X529358Y267583D01*
X529067Y267833D01*
X528900Y268208D01*
X528858Y268625D01*
X528942Y269167D01*
X529067Y269458D01*
X529275Y269750D01*
X529567Y269958D01*
X529858Y270000D01*
X530150Y269917D01*
X530358Y269708D01*
G01X516610Y233674D02*
Y238674D01*
X518610D01*
X519277Y238424D01*
X519777Y237841D01*
X519944Y237174D01*
X519777Y236507D01*
X519360Y236007D01*
X518610Y235757D01*
X516610D01*
G01X522960Y235341D02*
X524960D01*
G01X523877Y236424D02*
Y234257D01*
G01X527727Y234341D02*
X528394Y233924D01*
X529144Y233674D01*
X529810D01*
X530477Y233924D01*
X530977Y234341D01*
X531227Y234924D01*
X531060Y235507D01*
X530644Y236007D01*
X529894Y236341D01*
X528894Y236507D01*
X528310Y236841D01*
X528060Y237424D01*
X528227Y238007D01*
X528644Y238424D01*
X529227Y238674D01*
X529810D01*
X530394Y238507D01*
X530894Y238091D01*
G01X542510Y238257D02*
X542010Y238507D01*
X541427Y238674D01*
X540760D01*
X540010Y238424D01*
X539427Y238007D01*
X539010Y237507D01*
X538677Y236674D01*
X538594Y235924D01*
X538760Y235174D01*
X539010Y234674D01*
X539510Y234174D01*
X540094Y233841D01*
X540677Y233674D01*
X541260D01*
X541844Y233841D01*
X542344Y234091D01*
X542760Y234424D01*
G01X546277Y233674D02*
X545610Y233757D01*
X545027Y234091D01*
X544527Y234591D01*
X544194Y235174D01*
X544027Y235841D01*
Y236507D01*
X544194Y237174D01*
X544527Y237757D01*
X545027Y238257D01*
X545610Y238591D01*
X546277Y238674D01*
X546944Y238591D01*
X547527Y238257D01*
X548027Y237757D01*
X548360Y237174D01*
X548527Y236507D01*
Y235841D01*
X548360Y235174D01*
X548027Y234591D01*
X547527Y234091D01*
X546944Y233757D01*
X546277Y233674D01*
G01X549960D02*
Y238674D01*
X553794Y233674D01*
Y238674D01*
G01X555560Y233674D02*
Y238674D01*
X559394Y233674D01*
Y238674D01*
G01X517500Y294900D02*
X517458Y294567D01*
X517292Y294275D01*
X517042Y294025D01*
X516750Y293858D01*
X516417Y293775D01*
X516083D01*
X515750Y293858D01*
X515458Y294025D01*
X515208Y294275D01*
X515042Y294567D01*
X515000Y294900D01*
X515042Y295233D01*
X515208Y295525D01*
X515458Y295775D01*
X515750Y295942D01*
X516083Y296025D01*
X516417D01*
X516750Y295942D01*
X517042Y295775D01*
X517292Y295525D01*
X517458Y295233D01*
X517500Y294900D01*
G01X516833Y295233D02*
X517500Y295733D01*
G01X517000Y297083D02*
X517292Y297333D01*
X517458Y297667D01*
X517500Y298042D01*
X517458Y298375D01*
X517250Y298708D01*
X517000Y298917D01*
X516750Y298958D01*
X516458Y298875D01*
X516250Y298583D01*
X516167Y298292D01*
Y297917D01*
G01Y298292D02*
X516042Y298542D01*
X515833Y298750D01*
X515583Y298833D01*
X515333Y298750D01*
X515125Y298542D01*
X515000Y298167D01*
X515042Y297792D01*
X515208Y297417D01*
G01X517500Y301600D02*
X515000D01*
X516792Y300058D01*
Y302142D01*
G01X517500Y308400D02*
X517458Y308067D01*
X517292Y307775D01*
X517042Y307525D01*
X516750Y307358D01*
X516417Y307275D01*
X516083D01*
X515750Y307358D01*
X515458Y307525D01*
X515208Y307775D01*
X515042Y308067D01*
X515000Y308400D01*
X515042Y308733D01*
X515208Y309025D01*
X515458Y309275D01*
X515750Y309442D01*
X516083Y309525D01*
X516417D01*
X516750Y309442D01*
X517042Y309275D01*
X517292Y309025D01*
X517458Y308733D01*
X517500Y308400D01*
G01X516833Y308733D02*
X517500Y309233D01*
G01X517000Y310583D02*
X517292Y310833D01*
X517458Y311167D01*
X517500Y311542D01*
X517458Y311875D01*
X517250Y312208D01*
X517000Y312417D01*
X516750Y312458D01*
X516458Y312375D01*
X516250Y312083D01*
X516167Y311792D01*
Y311417D01*
G01Y311792D02*
X516042Y312042D01*
X515833Y312250D01*
X515583Y312333D01*
X515333Y312250D01*
X515125Y312042D01*
X515000Y311667D01*
X515042Y311292D01*
X515208Y310917D01*
G01X517000Y313683D02*
X517292Y313933D01*
X517458Y314267D01*
X517500Y314642D01*
X517458Y314975D01*
X517250Y315308D01*
X517000Y315517D01*
X516750Y315558D01*
X516458Y315475D01*
X516250Y315183D01*
X516167Y314892D01*
Y314517D01*
G01Y314892D02*
X516042Y315142D01*
X515833Y315350D01*
X515583Y315433D01*
X515333Y315350D01*
X515125Y315142D01*
X515000Y314767D01*
X515042Y314392D01*
X515208Y314017D01*
G01X498517Y325500D02*
Y328000D01*
X499558D01*
X499892Y327875D01*
X500100Y327708D01*
X500183Y327375D01*
X500100Y327042D01*
X499850Y326833D01*
X499558Y326708D01*
X498517D01*
G01X499558D02*
X500183Y325500D01*
G01X501533Y326000D02*
X501783Y325708D01*
X502117Y325542D01*
X502492Y325500D01*
X502825Y325542D01*
X503158Y325750D01*
X503367Y326000D01*
X503408Y326250D01*
X503325Y326542D01*
X503033Y326750D01*
X502742Y326833D01*
X502367D01*
G01X502742D02*
X502992Y326958D01*
X503200Y327167D01*
X503283Y327417D01*
X503200Y327667D01*
X502992Y327875D01*
X502617Y328000D01*
X502242Y327958D01*
X501867Y327792D01*
G01X505467Y325500D02*
X505550Y326042D01*
X505675Y326500D01*
X505842Y326917D01*
X506050Y327375D01*
X506383Y328000D01*
X504717D01*
G01X507858Y326542D02*
X508150Y326833D01*
X508400Y327000D01*
X508733Y327083D01*
X509025Y327000D01*
X509233Y326833D01*
X509400Y326583D01*
X509442Y326292D01*
X509400Y326042D01*
X509233Y325792D01*
X508983Y325583D01*
X508692Y325500D01*
X508358Y325583D01*
X508067Y325833D01*
X507900Y326208D01*
X507858Y326625D01*
X507942Y327167D01*
X508067Y327458D01*
X508275Y327750D01*
X508567Y327958D01*
X508858Y328000D01*
X509150Y327917D01*
X509358Y327708D01*
G01X520800Y328000D02*
Y324000D01*
X528200D01*
G01X498517Y321500D02*
Y324000D01*
X499558D01*
X499892Y323875D01*
X500100Y323708D01*
X500183Y323375D01*
X500100Y323042D01*
X499850Y322833D01*
X499558Y322708D01*
X498517D01*
G01X499558D02*
X500183Y321500D01*
G01X502950D02*
Y324000D01*
X501408Y322208D01*
X503492D01*
G01X505550Y321500D02*
X505842Y321542D01*
X506175Y321667D01*
X506383Y321875D01*
X506467Y322167D01*
X506383Y322458D01*
X506133Y322708D01*
X505758Y322833D01*
X505342D01*
X505092Y322917D01*
X504883Y323125D01*
X504800Y323417D01*
X504925Y323708D01*
X505217Y323917D01*
X505550Y324000D01*
X505883Y323917D01*
X506175Y323708D01*
X506300Y323417D01*
X506217Y323125D01*
X506008Y322917D01*
X505758Y322833D01*
X505342D01*
X504967Y322708D01*
X504717Y322458D01*
X504633Y322167D01*
X504717Y321875D01*
X504925Y321667D01*
X505258Y321542D01*
X505550Y321500D01*
G01X507858Y323583D02*
X508108Y323833D01*
X508400Y323958D01*
X508733Y324000D01*
X509150Y323917D01*
X509442Y323708D01*
X509525Y323458D01*
X509483Y323208D01*
X509317Y323000D01*
X508483Y322583D01*
X508108Y322292D01*
X507858Y321875D01*
X507775Y321500D01*
X509525D01*
G01X528200Y320000D02*
Y324000D01*
X520800D01*
G01X560208Y130565D02*
X560083Y130315D01*
X560000Y130023D01*
Y129690D01*
X560125Y129315D01*
X560333Y129023D01*
X560583Y128815D01*
X561000Y128648D01*
X561375Y128606D01*
X561750Y128690D01*
X562000Y128815D01*
X562250Y129065D01*
X562417Y129356D01*
X562500Y129648D01*
Y129940D01*
X562417Y130231D01*
X562292Y130481D01*
X562125Y130690D01*
G01X562500Y131790D02*
X560000D01*
X562500Y133706D01*
X560000D01*
G01X562500Y136348D02*
X560000D01*
X561792Y134806D01*
Y136890D01*
G01X566809Y120909D02*
Y327909D01*
X620709D01*
Y120909D01*
X566809D01*
G01X535400Y217000D02*
Y214500D01*
G01X534442Y217000D02*
X536358D01*
G01X539417Y216792D02*
X539167Y216917D01*
X538875Y217000D01*
X538542D01*
X538167Y216875D01*
X537875Y216667D01*
X537667Y216417D01*
X537500Y216000D01*
X537458Y215625D01*
X537542Y215250D01*
X537667Y215000D01*
X537917Y214750D01*
X538208Y214583D01*
X538500Y214500D01*
X538792D01*
X539083Y214583D01*
X539333Y214708D01*
X539542Y214875D01*
G01X542100Y214500D02*
Y217000D01*
X540558Y215208D01*
X542642D01*
G01X529135Y193777D02*
Y204977D01*
G01D02*
X547135D01*
G01D02*
Y193777D01*
G01X529135Y177777D02*
Y166577D01*
G01D02*
X547135D01*
G01D02*
Y177777D01*
G01X521989Y204962D02*
Y193762D01*
G01Y166562D02*
Y177762D01*
G01X532333Y265971D02*
Y261971D01*
X539733D01*
G01X532333Y270971D02*
Y266971D01*
X539733D01*
G01X541208Y244767D02*
X541083Y244517D01*
X541000Y244225D01*
Y243892D01*
X541125Y243517D01*
X541333Y243225D01*
X541583Y243017D01*
X542000Y242850D01*
X542375Y242808D01*
X542750Y242892D01*
X543000Y243017D01*
X543250Y243267D01*
X543417Y243558D01*
X543500Y243850D01*
Y244142D01*
X543417Y244433D01*
X543292Y244683D01*
X543125Y244892D01*
G01X543000Y246033D02*
X543292Y246283D01*
X543458Y246617D01*
X543500Y246992D01*
X543458Y247325D01*
X543250Y247658D01*
X543000Y247867D01*
X542750Y247908D01*
X542458Y247825D01*
X542250Y247533D01*
X542167Y247242D01*
Y246867D01*
G01Y247242D02*
X542042Y247492D01*
X541833Y247700D01*
X541583Y247783D01*
X541333Y247700D01*
X541125Y247492D01*
X541000Y247117D01*
X541042Y246742D01*
X541208Y246367D01*
G01X543125Y249133D02*
X543333Y249383D01*
X543458Y249675D01*
X543500Y250050D01*
X543417Y250425D01*
X543250Y250717D01*
X542958Y250925D01*
X542625Y250967D01*
X542292Y250883D01*
X542083Y250675D01*
X541917Y250383D01*
X541875Y250092D01*
X541917Y249800D01*
X542083Y249425D01*
X541000Y249550D01*
Y250675D01*
G01X543208Y252442D02*
X543417Y252733D01*
X543500Y253067D01*
X543417Y253400D01*
X543167Y253692D01*
X542792Y253900D01*
X542417Y253983D01*
X541958D01*
X541583Y253900D01*
X541250Y253692D01*
X541083Y253442D01*
X541000Y253150D01*
X541083Y252817D01*
X541250Y252567D01*
X541500Y252400D01*
X541833Y252317D01*
X542125Y252400D01*
X542417Y252608D01*
X542583Y252858D01*
X542625Y253150D01*
X542542Y253483D01*
X542333Y253733D01*
X541958Y253983D01*
G01X535511Y304007D02*
X522511D01*
G01D02*
Y290007D01*
G01D02*
X535511D01*
G01D02*
Y304007D01*
G01X535536Y319102D02*
X522536D01*
G01D02*
Y305102D01*
G01D02*
X535536D01*
G01D02*
Y319102D01*
G01X544000Y293517D02*
X541500D01*
Y294558D01*
X541625Y294892D01*
X541792Y295100D01*
X542125Y295183D01*
X542458Y295100D01*
X542667Y294850D01*
X542792Y294558D01*
Y293517D01*
G01Y294558D02*
X544000Y295183D01*
G01X543500Y296533D02*
X543792Y296783D01*
X543958Y297117D01*
X544000Y297492D01*
X543958Y297825D01*
X543750Y298158D01*
X543500Y298367D01*
X543250Y298408D01*
X542958Y298325D01*
X542750Y298033D01*
X542667Y297742D01*
Y297367D01*
G01Y297742D02*
X542542Y297992D01*
X542333Y298200D01*
X542083Y298283D01*
X541833Y298200D01*
X541625Y297992D01*
X541500Y297617D01*
X541542Y297242D01*
X541708Y296867D01*
G01X544000Y300467D02*
X543458Y300550D01*
X543000Y300675D01*
X542583Y300842D01*
X542125Y301050D01*
X541500Y301383D01*
Y299717D01*
G01X543708Y302942D02*
X543917Y303233D01*
X544000Y303567D01*
X543917Y303900D01*
X543667Y304192D01*
X543292Y304400D01*
X542917Y304483D01*
X542458D01*
X542083Y304400D01*
X541750Y304192D01*
X541583Y303942D01*
X541500Y303650D01*
X541583Y303317D01*
X541750Y303067D01*
X542000Y302900D01*
X542333Y302817D01*
X542625Y302900D01*
X542917Y303108D01*
X543083Y303358D01*
X543125Y303650D01*
X543042Y303983D01*
X542833Y304233D01*
X542458Y304483D01*
G01X540000Y298700D02*
X536000D01*
Y291300D01*
G01X528236Y328402D02*
Y324402D01*
X535636D01*
G01X528136Y332602D02*
Y328602D01*
X535536D01*
G01X541708Y280267D02*
X541583Y280017D01*
X541500Y279725D01*
Y279392D01*
X541625Y279017D01*
X541833Y278725D01*
X542083Y278517D01*
X542500Y278350D01*
X542875Y278308D01*
X543250Y278392D01*
X543500Y278517D01*
X543750Y278767D01*
X543917Y279058D01*
X544000Y279350D01*
Y279642D01*
X543917Y279933D01*
X543792Y280183D01*
X543625Y280392D01*
G01X543500Y281533D02*
X543792Y281783D01*
X543958Y282117D01*
X544000Y282492D01*
X543958Y282825D01*
X543750Y283158D01*
X543500Y283367D01*
X543250Y283408D01*
X542958Y283325D01*
X542750Y283033D01*
X542667Y282742D01*
Y282367D01*
G01Y282742D02*
X542542Y282992D01*
X542333Y283200D01*
X542083Y283283D01*
X541833Y283200D01*
X541625Y282992D01*
X541500Y282617D01*
X541542Y282242D01*
X541708Y281867D01*
G01X542958Y284758D02*
X542667Y285050D01*
X542500Y285300D01*
X542417Y285633D01*
X542500Y285925D01*
X542667Y286133D01*
X542917Y286300D01*
X543208Y286342D01*
X543458Y286300D01*
X543708Y286133D01*
X543917Y285883D01*
X544000Y285592D01*
X543917Y285258D01*
X543667Y284967D01*
X543292Y284800D01*
X542875Y284758D01*
X542333Y284842D01*
X542042Y284967D01*
X541750Y285175D01*
X541542Y285467D01*
X541500Y285758D01*
X541583Y286050D01*
X541792Y286258D01*
G01X541500Y288650D02*
X541583Y288317D01*
X541792Y288067D01*
X542042Y287900D01*
X542375Y287775D01*
X542750Y287733D01*
X543125Y287775D01*
X543458Y287900D01*
X543708Y288067D01*
X543917Y288317D01*
X544000Y288650D01*
X543917Y288983D01*
X543708Y289233D01*
X543458Y289400D01*
X543125Y289525D01*
X542750Y289567D01*
X542375Y289525D01*
X542042Y289400D01*
X541792Y289233D01*
X541583Y288983D01*
X541500Y288650D01*
G01X528236Y324102D02*
Y320102D01*
X535636D01*
G01X559000Y320417D02*
X556500D01*
Y321458D01*
X556625Y321792D01*
X556792Y322000D01*
X557125Y322083D01*
X557458Y322000D01*
X557667Y321750D01*
X557792Y321458D01*
Y320417D01*
G01Y321458D02*
X559000Y322083D01*
G01X558500Y323433D02*
X558792Y323683D01*
X558958Y324017D01*
X559000Y324392D01*
X558958Y324725D01*
X558750Y325058D01*
X558500Y325267D01*
X558250Y325308D01*
X557958Y325225D01*
X557750Y324933D01*
X557667Y324642D01*
Y324267D01*
G01Y324642D02*
X557542Y324892D01*
X557333Y325100D01*
X557083Y325183D01*
X556833Y325100D01*
X556625Y324892D01*
X556500Y324517D01*
X556542Y324142D01*
X556708Y323767D01*
G01X559000Y327367D02*
X558458Y327450D01*
X558000Y327575D01*
X557583Y327742D01*
X557125Y327950D01*
X556500Y328283D01*
Y326617D01*
G01X559000Y330550D02*
X558958Y330842D01*
X558833Y331175D01*
X558625Y331383D01*
X558333Y331467D01*
X558042Y331383D01*
X557792Y331133D01*
X557667Y330758D01*
Y330342D01*
X557583Y330092D01*
X557375Y329883D01*
X557083Y329800D01*
X556792Y329925D01*
X556583Y330217D01*
X556500Y330550D01*
X556583Y330883D01*
X556792Y331175D01*
X557083Y331300D01*
X557375Y331217D01*
X557583Y331008D01*
X557667Y330758D01*
Y330342D01*
X557792Y329967D01*
X558042Y329717D01*
X558333Y329633D01*
X558625Y329717D01*
X558833Y329925D01*
X558958Y330258D01*
X559000Y330550D01*
G01X546998Y325836D02*
Y319436D01*
G01D02*
X553998D01*
G01D02*
Y328136D01*
G01X546998Y332836D02*
Y325036D01*
G01X553998Y332836D02*
Y327636D01*
G01X531517Y349500D02*
Y352000D01*
X532558D01*
X532892Y351875D01*
X533100Y351708D01*
X533183Y351375D01*
X533100Y351042D01*
X532850Y350833D01*
X532558Y350708D01*
X531517D01*
G01X532558D02*
X533183Y349500D01*
G01X534533Y350000D02*
X534783Y349708D01*
X535117Y349542D01*
X535492Y349500D01*
X535825Y349542D01*
X536158Y349750D01*
X536367Y350000D01*
X536408Y350250D01*
X536325Y350542D01*
X536033Y350750D01*
X535742Y350833D01*
X535367D01*
G01X535742D02*
X535992Y350958D01*
X536200Y351167D01*
X536283Y351417D01*
X536200Y351667D01*
X535992Y351875D01*
X535617Y352000D01*
X535242Y351958D01*
X534867Y351792D01*
G01X537758Y350542D02*
X538050Y350833D01*
X538300Y351000D01*
X538633Y351083D01*
X538925Y351000D01*
X539133Y350833D01*
X539300Y350583D01*
X539342Y350292D01*
X539300Y350042D01*
X539133Y349792D01*
X538883Y349583D01*
X538592Y349500D01*
X538258Y349583D01*
X537967Y349833D01*
X537800Y350208D01*
X537758Y350625D01*
X537842Y351167D01*
X537967Y351458D01*
X538175Y351750D01*
X538467Y351958D01*
X538758Y352000D01*
X539050Y351917D01*
X539258Y351708D01*
G01X540858Y350542D02*
X541150Y350833D01*
X541400Y351000D01*
X541733Y351083D01*
X542025Y351000D01*
X542233Y350833D01*
X542400Y350583D01*
X542442Y350292D01*
X542400Y350042D01*
X542233Y349792D01*
X541983Y349583D01*
X541692Y349500D01*
X541358Y349583D01*
X541067Y349833D01*
X540900Y350208D01*
X540858Y350625D01*
X540942Y351167D01*
X541067Y351458D01*
X541275Y351750D01*
X541567Y351958D01*
X541858Y352000D01*
X542150Y351917D01*
X542358Y351708D01*
G01X535536Y332902D02*
Y336902D01*
X528136D01*
G01X531517Y341500D02*
Y344000D01*
X532558D01*
X532892Y343875D01*
X533100Y343708D01*
X533183Y343375D01*
X533100Y343042D01*
X532850Y342833D01*
X532558Y342708D01*
X531517D01*
G01X532558D02*
X533183Y341500D01*
G01X534533Y342000D02*
X534783Y341708D01*
X535117Y341542D01*
X535492Y341500D01*
X535825Y341542D01*
X536158Y341750D01*
X536367Y342000D01*
X536408Y342250D01*
X536325Y342542D01*
X536033Y342750D01*
X535742Y342833D01*
X535367D01*
G01X535742D02*
X535992Y342958D01*
X536200Y343167D01*
X536283Y343417D01*
X536200Y343667D01*
X535992Y343875D01*
X535617Y344000D01*
X535242Y343958D01*
X534867Y343792D01*
G01X538467Y341500D02*
X538550Y342042D01*
X538675Y342500D01*
X538842Y342917D01*
X539050Y343375D01*
X539383Y344000D01*
X537717D01*
G01X542150Y341500D02*
Y344000D01*
X540608Y342208D01*
X542692D01*
G01X531517Y345500D02*
Y348000D01*
X532558D01*
X532892Y347875D01*
X533100Y347708D01*
X533183Y347375D01*
X533100Y347042D01*
X532850Y346833D01*
X532558Y346708D01*
X531517D01*
G01X532558D02*
X533183Y345500D01*
G01X534533Y346000D02*
X534783Y345708D01*
X535117Y345542D01*
X535492Y345500D01*
X535825Y345542D01*
X536158Y345750D01*
X536367Y346000D01*
X536408Y346250D01*
X536325Y346542D01*
X536033Y346750D01*
X535742Y346833D01*
X535367D01*
G01X535742D02*
X535992Y346958D01*
X536200Y347167D01*
X536283Y347417D01*
X536200Y347667D01*
X535992Y347875D01*
X535617Y348000D01*
X535242Y347958D01*
X534867Y347792D01*
G01X537758Y346542D02*
X538050Y346833D01*
X538300Y347000D01*
X538633Y347083D01*
X538925Y347000D01*
X539133Y346833D01*
X539300Y346583D01*
X539342Y346292D01*
X539300Y346042D01*
X539133Y345792D01*
X538883Y345583D01*
X538592Y345500D01*
X538258Y345583D01*
X537967Y345833D01*
X537800Y346208D01*
X537758Y346625D01*
X537842Y347167D01*
X537967Y347458D01*
X538175Y347750D01*
X538467Y347958D01*
X538758Y348000D01*
X539050Y347917D01*
X539258Y347708D01*
G01X540733Y345875D02*
X540983Y345667D01*
X541275Y345542D01*
X541650Y345500D01*
X542025Y345583D01*
X542317Y345750D01*
X542525Y346042D01*
X542567Y346375D01*
X542483Y346708D01*
X542275Y346917D01*
X541983Y347083D01*
X541692Y347125D01*
X541400Y347083D01*
X541025Y346917D01*
X541150Y348000D01*
X542275D01*
G01X531517Y338000D02*
Y340500D01*
X532558D01*
X532892Y340375D01*
X533100Y340208D01*
X533183Y339875D01*
X533100Y339542D01*
X532850Y339333D01*
X532558Y339208D01*
X531517D01*
G01X532558D02*
X533183Y338000D01*
G01X534533Y338500D02*
X534783Y338208D01*
X535117Y338042D01*
X535492Y338000D01*
X535825Y338042D01*
X536158Y338250D01*
X536367Y338500D01*
X536408Y338750D01*
X536325Y339042D01*
X536033Y339250D01*
X535742Y339333D01*
X535367D01*
G01X535742D02*
X535992Y339458D01*
X536200Y339667D01*
X536283Y339917D01*
X536200Y340167D01*
X535992Y340375D01*
X535617Y340500D01*
X535242Y340458D01*
X534867Y340292D01*
G01X538467Y338000D02*
X538550Y338542D01*
X538675Y339000D01*
X538842Y339417D01*
X539050Y339875D01*
X539383Y340500D01*
X537717D01*
G01X540733Y338375D02*
X540983Y338167D01*
X541275Y338042D01*
X541650Y338000D01*
X542025Y338083D01*
X542317Y338250D01*
X542525Y338542D01*
X542567Y338875D01*
X542483Y339208D01*
X542275Y339417D01*
X541983Y339583D01*
X541692Y339625D01*
X541400Y339583D01*
X541025Y339417D01*
X541150Y340500D01*
X542275D01*
G01X553998Y332836D02*
X546998D01*
G01X532517Y431500D02*
Y434000D01*
X533558D01*
X533892Y433875D01*
X534100Y433708D01*
X534183Y433375D01*
X534100Y433042D01*
X533850Y432833D01*
X533558Y432708D01*
X532517D01*
G01X533558D02*
X534183Y431500D01*
G01X535533Y432000D02*
X535783Y431708D01*
X536117Y431542D01*
X536492Y431500D01*
X536825Y431542D01*
X537158Y431750D01*
X537367Y432000D01*
X537408Y432250D01*
X537325Y432542D01*
X537033Y432750D01*
X536742Y432833D01*
X536367D01*
G01X536742D02*
X536992Y432958D01*
X537200Y433167D01*
X537283Y433417D01*
X537200Y433667D01*
X536992Y433875D01*
X536617Y434000D01*
X536242Y433958D01*
X535867Y433792D01*
G01X538842Y431792D02*
X539133Y431583D01*
X539467Y431500D01*
X539800Y431583D01*
X540092Y431833D01*
X540300Y432208D01*
X540383Y432583D01*
Y433042D01*
X540300Y433417D01*
X540092Y433750D01*
X539842Y433917D01*
X539550Y434000D01*
X539217Y433917D01*
X538967Y433750D01*
X538800Y433500D01*
X538717Y433167D01*
X538800Y432875D01*
X539008Y432583D01*
X539258Y432417D01*
X539550Y432375D01*
X539883Y432458D01*
X540133Y432667D01*
X540383Y433042D01*
G01X542650Y431500D02*
Y434000D01*
X542150Y433500D01*
G01Y431500D02*
X543150D01*
G01X550000Y434700D02*
X546000D01*
Y427300D01*
G01X530110Y422082D02*
Y424582D01*
X531151D01*
X531485Y424457D01*
X531693Y424290D01*
X531776Y423957D01*
X531693Y423624D01*
X531443Y423415D01*
X531151Y423290D01*
X530110D01*
G01X531151D02*
X531776Y422082D01*
G01X533126Y422582D02*
X533376Y422290D01*
X533710Y422124D01*
X534085Y422082D01*
X534418Y422124D01*
X534751Y422332D01*
X534960Y422582D01*
X535001Y422832D01*
X534918Y423124D01*
X534626Y423332D01*
X534335Y423415D01*
X533960D01*
G01X534335D02*
X534585Y423540D01*
X534793Y423749D01*
X534876Y423999D01*
X534793Y424249D01*
X534585Y424457D01*
X534210Y424582D01*
X533835Y424540D01*
X533460Y424374D01*
G01X536435Y422374D02*
X536726Y422165D01*
X537060Y422082D01*
X537393Y422165D01*
X537685Y422415D01*
X537893Y422790D01*
X537976Y423165D01*
Y423624D01*
X537893Y423999D01*
X537685Y424332D01*
X537435Y424499D01*
X537143Y424582D01*
X536810Y424499D01*
X536560Y424332D01*
X536393Y424082D01*
X536310Y423749D01*
X536393Y423457D01*
X536601Y423165D01*
X536851Y422999D01*
X537143Y422957D01*
X537476Y423040D01*
X537726Y423249D01*
X537976Y423624D01*
G01X540243Y424582D02*
X539910Y424499D01*
X539660Y424290D01*
X539493Y424040D01*
X539368Y423707D01*
X539326Y423332D01*
X539368Y422957D01*
X539493Y422624D01*
X539660Y422374D01*
X539910Y422165D01*
X540243Y422082D01*
X540576Y422165D01*
X540826Y422374D01*
X540993Y422624D01*
X541118Y422957D01*
X541160Y423332D01*
X541118Y423707D01*
X540993Y424040D01*
X540826Y424290D01*
X540576Y424499D01*
X540243Y424582D01*
G01X549700Y417000D02*
Y421000D01*
X542300D01*
G01X604539Y419871D02*
Y421821D01*
X555239D01*
Y431771D01*
X557339D01*
Y444321D01*
X599539D01*
Y446271D01*
X659739D01*
Y419871D01*
X604539D01*
G01X558025Y448333D02*
X558358Y448125D01*
X558733Y448000D01*
X559067D01*
X559400Y448125D01*
X559650Y448333D01*
X559775Y448625D01*
X559692Y448917D01*
X559483Y449167D01*
X559108Y449333D01*
X558608Y449417D01*
X558317Y449583D01*
X558192Y449875D01*
X558275Y450167D01*
X558483Y450375D01*
X558775Y450500D01*
X559067D01*
X559358Y450417D01*
X559608Y450208D01*
G01X560750Y450500D02*
X561333Y448000D01*
X562000Y450500D01*
X562667Y448000D01*
X563250Y450500D01*
G01X565100Y448000D02*
Y450500D01*
X564600Y450000D01*
G01Y448000D02*
X565600D01*
G01X619500Y81017D02*
X617000D01*
Y82058D01*
X617125Y82392D01*
X617292Y82600D01*
X617625Y82683D01*
X617958Y82600D01*
X618167Y82350D01*
X618292Y82058D01*
Y81017D01*
G01Y82058D02*
X619500Y82683D01*
G01Y85450D02*
X617000D01*
X618792Y83908D01*
Y85992D01*
G01X619500Y88050D02*
X619458Y88342D01*
X619333Y88675D01*
X619125Y88883D01*
X618833Y88967D01*
X618542Y88883D01*
X618292Y88633D01*
X618167Y88258D01*
Y87842D01*
X618083Y87592D01*
X617875Y87383D01*
X617583Y87300D01*
X617292Y87425D01*
X617083Y87717D01*
X617000Y88050D01*
X617083Y88383D01*
X617292Y88675D01*
X617583Y88800D01*
X617875Y88717D01*
X618083Y88508D01*
X618167Y88258D01*
Y87842D01*
X618292Y87467D01*
X618542Y87217D01*
X618833Y87133D01*
X619125Y87217D01*
X619333Y87425D01*
X619458Y87758D01*
X619500Y88050D01*
G01X619000Y90233D02*
X619292Y90483D01*
X619458Y90817D01*
X619500Y91192D01*
X619458Y91525D01*
X619250Y91858D01*
X619000Y92067D01*
X618750Y92108D01*
X618458Y92025D01*
X618250Y91733D01*
X618167Y91442D01*
Y91067D01*
G01Y91442D02*
X618042Y91692D01*
X617833Y91900D01*
X617583Y91983D01*
X617333Y91900D01*
X617125Y91692D01*
X617000Y91317D01*
X617042Y90942D01*
X617208Y90567D01*
G01X626000Y70017D02*
X628500D01*
Y71683D01*
G01Y74783D02*
Y73117D01*
X626000D01*
Y74783D01*
G01X627208Y74117D02*
Y73117D01*
G01X628500Y76133D02*
X626000D01*
Y76967D01*
X626125Y77300D01*
X626292Y77550D01*
X626542Y77758D01*
X626833Y77925D01*
X627250Y77967D01*
X627667Y77925D01*
X627958Y77758D01*
X628208Y77550D01*
X628375Y77300D01*
X628500Y76967D01*
Y76133D01*
G01Y80150D02*
X626000D01*
X626500Y79650D01*
G01X628500D02*
Y80650D01*
G01X637088Y80203D02*
Y69403D01*
X631888D01*
Y80203D01*
X637088D01*
G01X633726Y218159D02*
X634059Y218692D01*
X634259Y219292D01*
Y219826D01*
X634059Y220359D01*
X633726Y220759D01*
X633259Y220959D01*
X632792Y220826D01*
X632392Y220492D01*
X632126Y219892D01*
X631992Y219092D01*
X631726Y218626D01*
X631259Y218426D01*
X630792Y218559D01*
X630459Y218892D01*
X630259Y219359D01*
Y219826D01*
X630392Y220292D01*
X630726Y220692D01*
G01X634259Y224159D02*
X630259D01*
G01X631592Y228759D02*
X634259D01*
G01X630526D02*
X630459Y228626D01*
X630326D01*
X630259Y228759D01*
X630326Y228892D01*
X630459D01*
X630526Y228759D01*
G01X630259Y233359D02*
X634259D01*
G01X631592Y232426D02*
Y234292D01*
G01X585967Y348500D02*
Y346000D01*
X587633D01*
G01X590733D02*
X589067D01*
Y348500D01*
X590733D01*
G01X590067Y347292D02*
X589067D01*
G01X592083Y346000D02*
Y348500D01*
X592917D01*
X593250Y348375D01*
X593500Y348208D01*
X593708Y347958D01*
X593875Y347667D01*
X593917Y347250D01*
X593875Y346833D01*
X593708Y346542D01*
X593500Y346292D01*
X593250Y346125D01*
X592917Y346000D01*
X592083D01*
G01X596100D02*
Y348500D01*
X595600Y348000D01*
G01Y346000D02*
X596600D01*
G01X598408Y347042D02*
X598700Y347333D01*
X598950Y347500D01*
X599283Y347583D01*
X599575Y347500D01*
X599783Y347333D01*
X599950Y347083D01*
X599992Y346792D01*
X599950Y346542D01*
X599783Y346292D01*
X599533Y346083D01*
X599242Y346000D01*
X598908Y346083D01*
X598617Y346333D01*
X598450Y346708D01*
X598408Y347125D01*
X598492Y347667D01*
X598617Y347958D01*
X598825Y348250D01*
X599117Y348458D01*
X599408Y348500D01*
X599700Y348417D01*
X599908Y348208D01*
G01X623285Y336676D02*
Y353376D01*
X602385D01*
Y336676D01*
X623285D01*
G01X599000Y384900D02*
X598958Y384567D01*
X598792Y384275D01*
X598542Y384025D01*
X598250Y383858D01*
X597917Y383775D01*
X597583D01*
X597250Y383858D01*
X596958Y384025D01*
X596708Y384275D01*
X596542Y384567D01*
X596500Y384900D01*
X596542Y385233D01*
X596708Y385525D01*
X596958Y385775D01*
X597250Y385942D01*
X597583Y386025D01*
X597917D01*
X598250Y385942D01*
X598542Y385775D01*
X598792Y385525D01*
X598958Y385233D01*
X599000Y384900D01*
G01X598333Y385233D02*
X599000Y385733D01*
G01X598500Y387083D02*
X598792Y387333D01*
X598958Y387667D01*
X599000Y388042D01*
X598958Y388375D01*
X598750Y388708D01*
X598500Y388917D01*
X598250Y388958D01*
X597958Y388875D01*
X597750Y388583D01*
X597667Y388292D01*
Y387917D01*
G01Y388292D02*
X597542Y388542D01*
X597333Y388750D01*
X597083Y388833D01*
X596833Y388750D01*
X596625Y388542D01*
X596500Y388167D01*
X596542Y387792D01*
X596708Y387417D01*
G01X599000Y391100D02*
X596500D01*
X597000Y390600D01*
G01X599000D02*
Y391600D01*
G01X623285Y380376D02*
Y397076D01*
X602385D01*
Y380376D01*
X623285D01*
G01X605000Y404017D02*
X602500D01*
Y405017D01*
X602625Y405350D01*
X602917Y405600D01*
X603250Y405683D01*
X603583Y405600D01*
X603833Y405392D01*
X603958Y405017D01*
Y404017D01*
G01X605000Y407117D02*
X602500D01*
Y408158D01*
X602625Y408492D01*
X602792Y408700D01*
X603125Y408783D01*
X603458Y408700D01*
X603667Y408450D01*
X603792Y408158D01*
Y407117D01*
G01Y408158D02*
X605000Y408783D01*
G01X603958Y410258D02*
X603667Y410550D01*
X603500Y410800D01*
X603417Y411133D01*
X603500Y411425D01*
X603667Y411633D01*
X603917Y411800D01*
X604208Y411842D01*
X604458Y411800D01*
X604708Y411633D01*
X604917Y411383D01*
X605000Y411092D01*
X604917Y410758D01*
X604667Y410467D01*
X604292Y410300D01*
X603875Y410258D01*
X603333Y410342D01*
X603042Y410467D01*
X602750Y410675D01*
X602542Y410967D01*
X602500Y411258D01*
X602583Y411550D01*
X602792Y411758D01*
G01X604625Y413233D02*
X604833Y413483D01*
X604958Y413775D01*
X605000Y414150D01*
X604917Y414525D01*
X604750Y414817D01*
X604458Y415025D01*
X604125Y415067D01*
X603792Y414983D01*
X603583Y414775D01*
X603417Y414483D01*
X603375Y414192D01*
X603417Y413900D01*
X603583Y413525D01*
X602500Y413650D01*
Y414775D01*
G01X609500Y404017D02*
X607000D01*
Y405017D01*
X607125Y405350D01*
X607417Y405600D01*
X607750Y405683D01*
X608083Y405600D01*
X608333Y405392D01*
X608458Y405017D01*
Y404017D01*
G01X609500Y407117D02*
X607000D01*
Y408158D01*
X607125Y408492D01*
X607292Y408700D01*
X607625Y408783D01*
X607958Y408700D01*
X608167Y408450D01*
X608292Y408158D01*
Y407117D01*
G01Y408158D02*
X609500Y408783D01*
G01X608458Y410258D02*
X608167Y410550D01*
X608000Y410800D01*
X607917Y411133D01*
X608000Y411425D01*
X608167Y411633D01*
X608417Y411800D01*
X608708Y411842D01*
X608958Y411800D01*
X609208Y411633D01*
X609417Y411383D01*
X609500Y411092D01*
X609417Y410758D01*
X609167Y410467D01*
X608792Y410300D01*
X608375Y410258D01*
X607833Y410342D01*
X607542Y410467D01*
X607250Y410675D01*
X607042Y410967D01*
X607000Y411258D01*
X607083Y411550D01*
X607292Y411758D01*
G01X609500Y414650D02*
X607000D01*
X608792Y413108D01*
Y415192D01*
G01X625333Y398467D02*
X625133Y398067D01*
X625000Y397600D01*
Y397067D01*
X625200Y396467D01*
X625533Y396000D01*
X625933Y395667D01*
X626600Y395400D01*
X627200Y395333D01*
X627800Y395467D01*
X628200Y395667D01*
X628600Y396067D01*
X628867Y396533D01*
X629000Y397000D01*
Y397467D01*
X628867Y397933D01*
X628667Y398333D01*
X628400Y398667D01*
G01X600000Y398333D02*
Y395667D01*
X596000D01*
Y398333D01*
G01X597933Y397267D02*
Y395667D01*
G54D17*
G01X40109Y365933D02*
X36109D01*
G01X36128Y377132D02*
X40128D01*
G01X43807Y390868D02*
X47807D01*
G01X544500Y260971D02*
X540500D01*
G01Y271971D02*
X544500D01*
G01X616100Y74500D02*
X617200D01*
G01X618800D02*
X619900D01*
G01X610898Y405836D02*
X611998D01*
G01X613598D02*
X614698D01*
G01X615898Y405936D02*
X616998D01*
G01X618598D02*
X619698D01*
M02*
